FILE_TYPE = MACRO_DRAWING;
SET COLOR_WIRE YELLOW;
SET COLOR_PROP ORANGE;
SET COLOR_DOT WHITE;
SET COLOR_ARC YELLOW;
SET COLOR_BODY GREEN;
SET COLOR_NOTE PURPLE;
SET PROP_DISPLAY VALUE;
SET PAGE_NUMBER P90;
FORCEADD GND..1
(-2225 2175);
FORCEPROP 3 LASTPIN (-2225 2225) SIG_NAME GND\g
J 0
(-2215 2235);
DISPLAY 0.659574 (-2215 2235);
PAINT MONO (-2215 2235);
DISPLAY INVISIBLE (-2215 2235);
FORCEPROP 1 LAST SIZE 1B
J 0
(-2150 2125);
DISPLAY 0.851064 (-2150 2125);
PAINT GREEN (-2150 2125);
DISPLAY INVISIBLE (-2150 2125);
FORCEPROP 2 LAST CDS_LIB mstr_symbols
J 0
(-2225 2175);
DISPLAY 0.723404 (-2225 2175);
DISPLAY INVISIBLE (-2225 2175);
FORCEPROP 1 LAST BODY_TYPE PLUMBING
J 0
(-2270 2132);
DISPLAY 0.340426 (-2270 2132);
PAINT GREEN (-2270 2132);
DISPLAY INVISIBLE (-2270 2132);
FORCEPROP 1 LAST PATH I150
J 0
(-2150 2175);
DISPLAY 0.872340 (-2150 2175);
PAINT GREEN (-2150 2175);
DISPLAY INVISIBLE (-2150 2175);
FORCEPROP 1 LAST VOLTAGE 0.0
J 0
(-2270 2132);
DISPLAY 0.723404 (-2270 2132);
PAINT SKYBLUE (-2270 2132);
DISPLAY INVISIBLE (-2270 2132);
FORCEPROP 1 LAST HDL_POWER GND
J 0
(-2225 2325);
DISPLAY 0.851064 (-2225 2325);
PAINT GREEN (-2225 2325);
DISPLAY INVISIBLE (-2225 2325);
FORCEADD GND..1
(-425 1950);
FORCEPROP 3 LASTPIN (-425 2000) SIG_NAME GND\g
J 0
(-415 2010);
DISPLAY 0.659574 (-415 2010);
PAINT MONO (-415 2010);
DISPLAY INVISIBLE (-415 2010);
FORCEPROP 2 LAST CDS_LIB mstr_symbols
J 0
(-425 1950);
DISPLAY 0.723404 (-425 1950);
DISPLAY INVISIBLE (-425 1950);
FORCEPROP 1 LAST SIZE 1B
J 0
(-350 1900);
DISPLAY 0.851064 (-350 1900);
PAINT GREEN (-350 1900);
DISPLAY INVISIBLE (-350 1900);
FORCEPROP 1 LAST BODY_TYPE PLUMBING
J 0
(-470 1907);
DISPLAY 0.340426 (-470 1907);
PAINT GREEN (-470 1907);
DISPLAY INVISIBLE (-470 1907);
FORCEPROP 1 LAST PATH I152
J 0
(-350 1950);
DISPLAY 0.872340 (-350 1950);
PAINT GREEN (-350 1950);
DISPLAY INVISIBLE (-350 1950);
FORCEPROP 1 LAST VOLTAGE 0.0
J 0
(-470 1907);
DISPLAY 0.723404 (-470 1907);
PAINT SKYBLUE (-470 1907);
DISPLAY INVISIBLE (-470 1907);
FORCEPROP 1 LAST HDL_POWER GND
J 0
(-425 2100);
DISPLAY 0.851064 (-425 2100);
PAINT GREEN (-425 2100);
DISPLAY INVISIBLE (-425 2100);
FORCEADD OFFPAGE..5
(-8375 2275);
FORCEPROP 2 LAST $XR0 15 
J 0
(-8629 2275);
DISPLAY 0.638298 (-8629 2275);
PAINT MONO (-8629 2275);
FORCEPROP 2 LAST CDS_LIB mstr_standard
J 0
(-8375 2275);
DISPLAY 0.808511 (-8375 2275);
DISPLAY INVISIBLE (-8375 2275);
FORCEPROP 1 LAST OFFPAGE TRUE
J 0
(-8050 2150);
DISPLAY 0.872340 (-8050 2150);
PAINT GREEN (-8050 2150);
DISPLAY INVISIBLE (-8050 2150);
FORCEPROP 1 LAST COMMENT_BODY TRUE
J 0
(-8275 2200);
DISPLAY 0.872340 (-8275 2200);
PAINT GREEN (-8275 2200);
DISPLAY INVISIBLE (-8275 2200);
FORCEPROP 2 LAST PATH I167
J 0
(-8325 2350);
DISPLAY 0.808511 (-8325 2350);
DISPLAY INVISIBLE (-8325 2350);
FORCEADD OFFPAGE..5
(-8375 2325);
FORCEPROP 2 LAST $XR0 15 
J 0
(-8629 2325);
DISPLAY 0.638298 (-8629 2325);
PAINT MONO (-8629 2325);
FORCEPROP 2 LAST CDS_LIB mstr_standard
J 0
(-8375 2325);
DISPLAY 0.808511 (-8375 2325);
DISPLAY INVISIBLE (-8375 2325);
FORCEPROP 1 LAST OFFPAGE TRUE
J 0
(-8050 2200);
DISPLAY 0.872340 (-8050 2200);
PAINT GREEN (-8050 2200);
DISPLAY INVISIBLE (-8050 2200);
FORCEPROP 1 LAST COMMENT_BODY TRUE
J 0
(-8275 2250);
DISPLAY 0.872340 (-8275 2250);
PAINT GREEN (-8275 2250);
DISPLAY INVISIBLE (-8275 2250);
FORCEPROP 2 LAST PATH I168
J 0
(-8325 2400);
DISPLAY 0.808511 (-8325 2400);
DISPLAY INVISIBLE (-8325 2400);
FORCEADD VCC_CORE..1
(-8550 3775);
FORCEPROP 3 LASTPIN (-8550 3725) SIG_NAME P3V3_STBY\g
J 0
(-8540 3735);
DISPLAY 0.659574 (-8540 3735);
PAINT MONO (-8540 3735);
DISPLAY INVISIBLE (-8540 3735);
FORCEPROP 1 LAST HDL_POWER P3V3_STBY
J 1
(-8550 3825);
DISPLAY 0.489362 (-8550 3825);
PAINT GREEN (-8550 3825);
FORCEPROP 2 LAST CDS_LIB mstr_symbols
J 0
(-8550 3775);
PAINT MONO (-8550 3775);
DISPLAY INVISIBLE (-8550 3775);
FORCEPROP 1 LAST PATH I175
J 0
(-8500 3800);
DISPLAY 0.872340 (-8500 3800);
PAINT GREEN (-8500 3800);
DISPLAY INVISIBLE (-8500 3800);
FORCEPROP 0 LAST VOLTAGE 3.3
J 0
(-8825 3925);
DISPLAY 1.021277 (-8825 3925);
PAINT SKYBLUE (-8825 3925);
DISPLAY INVISIBLE (-8825 3925);
FORCEPROP 2 LAST ROOM PVCCINFAON_CPU0_CTRL
J 0
(-8550 3875);
DISPLAY 0.808511 (-8550 3875);
PAINT RED (-8550 3875);
DISPLAY INVISIBLE (-8550 3875);
FORCEADD OFFPAGE..1
(-8175 3425);
FORCEPROP 2 LAST $XR0 15 
J 0
(-8396 3425);
DISPLAY 0.638298 (-8396 3425);
PAINT MONO (-8396 3425);
FORCEPROP 2 LAST CDS_LIB mstr_standard
J 0
(-8175 3425);
DISPLAY 0.808511 (-8175 3425);
DISPLAY INVISIBLE (-8175 3425);
FORCEPROP 1 LAST OFFPAGE TRUE
J 0
(-7850 3300);
DISPLAY 0.872340 (-7850 3300);
PAINT GREEN (-7850 3300);
DISPLAY INVISIBLE (-7850 3300);
FORCEPROP 1 LAST COMMENT_BODY TRUE
J 0
(-8050 3325);
DISPLAY 0.872340 (-8050 3325);
PAINT GREEN (-8050 3325);
DISPLAY INVISIBLE (-8050 3325);
FORCEPROP 2 LAST PATH I176
J 0
(-8375 3650);
DISPLAY 0.808511 (-8375 3650);
DISPLAY INVISIBLE (-8375 3650);
FORCEADD TAP..1
R 2
(-7775 3525);
FORCEPROP 3 LASTPIN (-7725 3525) SIG_NAME M_F_CPU0_SB_CB<0>
J 0
(-7715 3535);
DISPLAY 0.659574 (-7715 3535);
PAINT MONO (-7715 3535);
DISPLAY INVISIBLE (-7715 3535);
FORCEPROP 1 LASTPIN (-7725 3525) BN 0
J 2
(-7713 3533);
DISPLAY 0.489362 (-7713 3533);
PAINT GREEN (-7713 3533);
FORCEPROP 2 LAST CDS_LIB mstr_standard
J 0
(-7775 3525);
DISPLAY 0.723404 (-7775 3525);
PAINT MONO (-7775 3525);
DISPLAY INVISIBLE (-7775 3525);
FORCEPROP 1 LAST BODY_TYPE PLUMBING
J 2
(-7775 3575);
DISPLAY 0.872340 (-7775 3575);
PAINT GREEN (-7775 3575);
DISPLAY INVISIBLE (-7775 3575);
FORCEPROP 1 LAST HDL_TAP TRUE
J 2
(-8100 3400);
DISPLAY 0.872340 (-8100 3400);
DISPLAY INVISIBLE (-8100 3400);
FORCEPROP 1 LAST PATH I177
J 2
(-7773 3525);
DISPLAY 0.872340 (-7773 3525);
PAINT GREEN (-7773 3525);
DISPLAY INVISIBLE (-7773 3525);
FORCEADD TAP..1
R 2
(-7775 3575);
FORCEPROP 3 LASTPIN (-7725 3575) SIG_NAME M_F_CPU0_SB_CB<1>
J 0
(-7715 3585);
DISPLAY 0.659574 (-7715 3585);
PAINT MONO (-7715 3585);
DISPLAY INVISIBLE (-7715 3585);
FORCEPROP 1 LASTPIN (-7725 3575) BN 1
J 2
(-7713 3583);
DISPLAY 0.489362 (-7713 3583);
PAINT GREEN (-7713 3583);
FORCEPROP 2 LAST CDS_LIB mstr_standard
J 0
(-7775 3575);
DISPLAY 0.723404 (-7775 3575);
PAINT MONO (-7775 3575);
DISPLAY INVISIBLE (-7775 3575);
FORCEPROP 1 LAST BODY_TYPE PLUMBING
J 2
(-7775 3625);
DISPLAY 0.872340 (-7775 3625);
PAINT GREEN (-7775 3625);
DISPLAY INVISIBLE (-7775 3625);
FORCEPROP 1 LAST HDL_TAP TRUE
J 2
(-8100 3450);
DISPLAY 0.872340 (-8100 3450);
DISPLAY INVISIBLE (-8100 3450);
FORCEPROP 1 LAST PATH I178
J 2
(-7773 3575);
DISPLAY 0.872340 (-7773 3575);
PAINT GREEN (-7773 3575);
DISPLAY INVISIBLE (-7773 3575);
FORCEADD TAP..1
R 2
(-7775 3625);
FORCEPROP 3 LASTPIN (-7725 3625) SIG_NAME M_F_CPU0_SB_CB<2>
J 0
(-7715 3635);
DISPLAY 0.659574 (-7715 3635);
PAINT MONO (-7715 3635);
DISPLAY INVISIBLE (-7715 3635);
FORCEPROP 1 LASTPIN (-7725 3625) BN 2
J 2
(-7713 3633);
DISPLAY 0.489362 (-7713 3633);
PAINT GREEN (-7713 3633);
FORCEPROP 2 LAST CDS_LIB mstr_standard
J 0
(-7775 3625);
DISPLAY 0.723404 (-7775 3625);
PAINT MONO (-7775 3625);
DISPLAY INVISIBLE (-7775 3625);
FORCEPROP 1 LAST BODY_TYPE PLUMBING
J 2
(-7775 3675);
DISPLAY 0.872340 (-7775 3675);
PAINT GREEN (-7775 3675);
DISPLAY INVISIBLE (-7775 3675);
FORCEPROP 1 LAST HDL_TAP TRUE
J 2
(-8100 3500);
DISPLAY 0.872340 (-8100 3500);
DISPLAY INVISIBLE (-8100 3500);
FORCEPROP 1 LAST PATH I179
J 2
(-7773 3625);
DISPLAY 0.872340 (-7773 3625);
PAINT GREEN (-7773 3625);
DISPLAY INVISIBLE (-7773 3625);
FORCEADD OFFPAGE..6
(-8375 3925);
FORCEPROP 2 LAST $XR0 15 
J 0
(-8654 3925);
DISPLAY 0.638298 (-8654 3925);
PAINT MONO (-8654 3925);
FORCEPROP 2 LAST CDS_LIB mstr_standard
J 0
(-8375 3925);
DISPLAY 0.723404 (-8375 3925);
PAINT MONO (-8375 3925);
DISPLAY INVISIBLE (-8375 3925);
FORCEPROP 1 LAST OFFPAGE TRUE
J 0
(-8050 3800);
DISPLAY 0.872340 (-8050 3800);
PAINT GREEN (-8050 3800);
DISPLAY INVISIBLE (-8050 3800);
FORCEPROP 1 LAST COMMENT_BODY TRUE
J 0
(-8275 3850);
DISPLAY 0.872340 (-8275 3850);
PAINT GREEN (-8275 3850);
DISPLAY INVISIBLE (-8275 3850);
FORCEPROP 2 LAST PATH I180
J 0
(-8325 4000);
DISPLAY 0.808511 (-8325 4000);
DISPLAY INVISIBLE (-8325 4000);
FORCEADD OFFPAGE..6
(-8375 4375);
FORCEPROP 2 LAST $XR0 15 
J 0
(-8654 4375);
DISPLAY 0.638298 (-8654 4375);
PAINT MONO (-8654 4375);
FORCEPROP 2 LAST CDS_LIB mstr_standard
J 0
(-8375 4375);
DISPLAY 0.723404 (-8375 4375);
PAINT MONO (-8375 4375);
DISPLAY INVISIBLE (-8375 4375);
FORCEPROP 1 LAST OFFPAGE TRUE
J 0
(-8050 4250);
DISPLAY 0.872340 (-8050 4250);
PAINT GREEN (-8050 4250);
DISPLAY INVISIBLE (-8050 4250);
FORCEPROP 1 LAST COMMENT_BODY TRUE
J 0
(-8275 4300);
DISPLAY 0.872340 (-8275 4300);
PAINT GREEN (-8275 4300);
DISPLAY INVISIBLE (-8275 4300);
FORCEPROP 2 LAST PATH I181
J 0
(-8325 4450);
DISPLAY 0.808511 (-8325 4450);
DISPLAY INVISIBLE (-8325 4450);
FORCEADD OFFPAGE..1
(-8375 4575);
FORCEPROP 2 LAST $XR0 15 
J 0
(-8626 4575);
DISPLAY 0.638298 (-8626 4575);
PAINT MONO (-8626 4575);
FORCEPROP 2 LAST CDS_LIB mstr_standard
J 0
(-8375 4575);
DISPLAY 0.808511 (-8375 4575);
DISPLAY INVISIBLE (-8375 4575);
FORCEPROP 1 LAST OFFPAGE TRUE
J 0
(-8050 4450);
DISPLAY 0.872340 (-8050 4450);
PAINT GREEN (-8050 4450);
DISPLAY INVISIBLE (-8050 4450);
FORCEPROP 1 LAST COMMENT_BODY TRUE
J 0
(-8250 4475);
DISPLAY 0.872340 (-8250 4475);
PAINT GREEN (-8250 4475);
DISPLAY INVISIBLE (-8250 4475);
FORCEPROP 2 LAST PATH I182
J 0
(-8325 4650);
DISPLAY 0.808511 (-8325 4650);
DISPLAY INVISIBLE (-8325 4650);
FORCEADD OFFPAGE..1
(-8375 4475);
FORCEPROP 2 LAST $XR0 15 
J 0
(-8626 4475);
DISPLAY 0.638298 (-8626 4475);
PAINT MONO (-8626 4475);
FORCEPROP 2 LAST CDS_LIB mstr_standard
J 0
(-8375 4475);
DISPLAY 0.723404 (-8375 4475);
PAINT MONO (-8375 4475);
DISPLAY INVISIBLE (-8375 4475);
FORCEPROP 1 LAST OFFPAGE TRUE
J 0
(-8050 4350);
DISPLAY 0.872340 (-8050 4350);
PAINT GREEN (-8050 4350);
DISPLAY INVISIBLE (-8050 4350);
FORCEPROP 1 LAST COMMENT_BODY TRUE
J 0
(-8250 4375);
DISPLAY 0.872340 (-8250 4375);
PAINT GREEN (-8250 4375);
DISPLAY INVISIBLE (-8250 4375);
FORCEPROP 2 LAST PATH I183
J 0
(-8325 4550);
DISPLAY 0.808511 (-8325 4550);
DISPLAY INVISIBLE (-8325 4550);
FORCEADD OFFPAGE..1
(-8375 4425);
FORCEPROP 2 LAST $XR0 15 
J 0
(-8626 4425);
DISPLAY 0.638298 (-8626 4425);
PAINT MONO (-8626 4425);
FORCEPROP 2 LAST CDS_LIB mstr_standard
J 0
(-8375 4425);
DISPLAY 0.808511 (-8375 4425);
DISPLAY INVISIBLE (-8375 4425);
FORCEPROP 1 LAST OFFPAGE TRUE
J 0
(-8050 4300);
DISPLAY 0.872340 (-8050 4300);
PAINT GREEN (-8050 4300);
DISPLAY INVISIBLE (-8050 4300);
FORCEPROP 1 LAST COMMENT_BODY TRUE
J 0
(-8250 4325);
DISPLAY 0.872340 (-8250 4325);
PAINT GREEN (-8250 4325);
DISPLAY INVISIBLE (-8250 4325);
FORCEPROP 2 LAST PATH I184
J 0
(-8325 4500);
DISPLAY 0.808511 (-8325 4500);
DISPLAY INVISIBLE (-8325 4500);
FORCEADD OFFPAGE..1
(-8375 4625);
FORCEPROP 2 LAST $XR0 15 
J 0
(-8626 4625);
DISPLAY 0.638298 (-8626 4625);
PAINT MONO (-8626 4625);
FORCEPROP 2 LAST CDS_LIB mstr_standard
J 0
(-8375 4625);
DISPLAY 0.723404 (-8375 4625);
PAINT MONO (-8375 4625);
DISPLAY INVISIBLE (-8375 4625);
FORCEPROP 1 LAST OFFPAGE TRUE
J 0
(-8050 4500);
DISPLAY 0.872340 (-8050 4500);
PAINT GREEN (-8050 4500);
DISPLAY INVISIBLE (-8050 4500);
FORCEPROP 1 LAST COMMENT_BODY TRUE
J 0
(-8250 4525);
DISPLAY 0.872340 (-8250 4525);
PAINT GREEN (-8250 4525);
DISPLAY INVISIBLE (-8250 4525);
FORCEPROP 2 LAST PATH I185
J 0
(-8325 4700);
DISPLAY 0.808511 (-8325 4700);
DISPLAY INVISIBLE (-8325 4700);
FORCEADD OFFPAGE..1
(-8375 4875);
FORCEPROP 2 LAST $XR0 15 
J 0
(-8626 4875);
DISPLAY 0.638298 (-8626 4875);
PAINT MONO (-8626 4875);
FORCEPROP 2 LAST CDS_LIB mstr_standard
J 0
(-8375 4875);
DISPLAY 0.808511 (-8375 4875);
DISPLAY INVISIBLE (-8375 4875);
FORCEPROP 1 LAST OFFPAGE TRUE
J 0
(-8050 4750);
DISPLAY 0.872340 (-8050 4750);
PAINT GREEN (-8050 4750);
DISPLAY INVISIBLE (-8050 4750);
FORCEPROP 1 LAST COMMENT_BODY TRUE
J 0
(-8250 4775);
DISPLAY 0.872340 (-8250 4775);
PAINT GREEN (-8250 4775);
DISPLAY INVISIBLE (-8250 4775);
FORCEPROP 2 LAST PATH I186
J 0
(-8325 4950);
DISPLAY 0.808511 (-8325 4950);
DISPLAY INVISIBLE (-8325 4950);
FORCEADD OFFPAGE..1
(-8375 4775);
FORCEPROP 2 LAST $XR0 15 
J 0
(-8626 4775);
DISPLAY 0.638298 (-8626 4775);
PAINT MONO (-8626 4775);
FORCEPROP 2 LAST CDS_LIB mstr_standard
J 0
(-8375 4775);
DISPLAY 0.723404 (-8375 4775);
PAINT MONO (-8375 4775);
DISPLAY INVISIBLE (-8375 4775);
FORCEPROP 1 LAST OFFPAGE TRUE
J 0
(-8050 4650);
DISPLAY 0.872340 (-8050 4650);
PAINT GREEN (-8050 4650);
DISPLAY INVISIBLE (-8050 4650);
FORCEPROP 1 LAST COMMENT_BODY TRUE
J 0
(-8250 4675);
DISPLAY 0.872340 (-8250 4675);
PAINT GREEN (-8250 4675);
DISPLAY INVISIBLE (-8250 4675);
FORCEPROP 2 LAST PATH I187
J 0
(-8325 4850);
DISPLAY 0.808511 (-8325 4850);
DISPLAY INVISIBLE (-8325 4850);
FORCEADD OFFPAGE..1
(-8375 4725);
FORCEPROP 2 LAST $XR0 15 
J 0
(-8626 4725);
DISPLAY 0.638298 (-8626 4725);
PAINT MONO (-8626 4725);
FORCEPROP 2 LAST CDS_LIB mstr_standard
J 0
(-8375 4725);
DISPLAY 0.808511 (-8375 4725);
DISPLAY INVISIBLE (-8375 4725);
FORCEPROP 1 LAST OFFPAGE TRUE
J 0
(-8050 4600);
DISPLAY 0.872340 (-8050 4600);
PAINT GREEN (-8050 4600);
DISPLAY INVISIBLE (-8050 4600);
FORCEPROP 1 LAST COMMENT_BODY TRUE
J 0
(-8250 4625);
DISPLAY 0.872340 (-8250 4625);
PAINT GREEN (-8250 4625);
DISPLAY INVISIBLE (-8250 4625);
FORCEPROP 2 LAST PATH I188
J 0
(-8325 4800);
DISPLAY 0.808511 (-8325 4800);
DISPLAY INVISIBLE (-8325 4800);
FORCEADD OFFPAGE..1
(-8375 4925);
FORCEPROP 2 LAST $XR0 15 
J 0
(-8626 4925);
DISPLAY 0.638298 (-8626 4925);
PAINT MONO (-8626 4925);
FORCEPROP 2 LAST CDS_LIB mstr_standard
J 0
(-8375 4925);
DISPLAY 0.723404 (-8375 4925);
PAINT MONO (-8375 4925);
DISPLAY INVISIBLE (-8375 4925);
FORCEPROP 1 LAST OFFPAGE TRUE
J 0
(-8050 4800);
DISPLAY 0.872340 (-8050 4800);
PAINT GREEN (-8050 4800);
DISPLAY INVISIBLE (-8050 4800);
FORCEPROP 1 LAST COMMENT_BODY TRUE
J 0
(-8250 4825);
DISPLAY 0.872340 (-8250 4825);
PAINT GREEN (-8250 4825);
DISPLAY INVISIBLE (-8250 4825);
FORCEPROP 2 LAST PATH I189
J 0
(-8325 5000);
DISPLAY 0.808511 (-8325 5000);
DISPLAY INVISIBLE (-8325 5000);
FORCEADD OFFPAGE..1
(-8375 5375);
FORCEPROP 2 LAST $XR0 15 
J 0
(-8626 5375);
DISPLAY 0.638298 (-8626 5375);
PAINT MONO (-8626 5375);
FORCEPROP 2 LAST CDS_LIB mstr_standard
J 0
(-8375 5375);
DISPLAY 0.723404 (-8375 5375);
PAINT MONO (-8375 5375);
DISPLAY INVISIBLE (-8375 5375);
FORCEPROP 1 LAST OFFPAGE TRUE
J 0
(-8050 5250);
DISPLAY 0.872340 (-8050 5250);
PAINT GREEN (-8050 5250);
DISPLAY INVISIBLE (-8050 5250);
FORCEPROP 1 LAST COMMENT_BODY TRUE
J 0
(-8250 5275);
DISPLAY 0.872340 (-8250 5275);
PAINT GREEN (-8250 5275);
DISPLAY INVISIBLE (-8250 5275);
FORCEPROP 2 LAST PATH I190
J 0
(-8325 5450);
DISPLAY 0.808511 (-8325 5450);
DISPLAY INVISIBLE (-8325 5450);
FORCEADD OFFPAGE..1
(-8375 5775);
FORCEPROP 2 LAST $XR0 15 
J 0
(-8626 5775);
DISPLAY 0.638298 (-8626 5775);
PAINT MONO (-8626 5775);
FORCEPROP 2 LAST CDS_LIB mstr_standard
J 0
(-8375 5775);
DISPLAY 0.723404 (-8375 5775);
PAINT MONO (-8375 5775);
DISPLAY INVISIBLE (-8375 5775);
FORCEPROP 1 LAST OFFPAGE TRUE
J 0
(-8050 5650);
DISPLAY 0.872340 (-8050 5650);
PAINT GREEN (-8050 5650);
DISPLAY INVISIBLE (-8050 5650);
FORCEPROP 1 LAST COMMENT_BODY TRUE
J 0
(-8250 5675);
DISPLAY 0.872340 (-8250 5675);
PAINT GREEN (-8250 5675);
DISPLAY INVISIBLE (-8250 5675);
FORCEPROP 2 LAST PATH I191
J 0
(-8325 5850);
DISPLAY 0.808511 (-8325 5850);
DISPLAY INVISIBLE (-8325 5850);
FORCEADD TAP..1
R 2
(-7775 3725);
FORCEPROP 3 LASTPIN (-7725 3725) SIG_NAME M_F_CPU0_SB_CB<4>
J 0
(-7715 3735);
DISPLAY 0.659574 (-7715 3735);
PAINT MONO (-7715 3735);
DISPLAY INVISIBLE (-7715 3735);
FORCEPROP 1 LASTPIN (-7725 3725) BN 4
J 2
(-7713 3733);
DISPLAY 0.489362 (-7713 3733);
PAINT GREEN (-7713 3733);
FORCEPROP 2 LAST CDS_LIB mstr_standard
J 0
(-7775 3725);
DISPLAY 0.723404 (-7775 3725);
PAINT MONO (-7775 3725);
DISPLAY INVISIBLE (-7775 3725);
FORCEPROP 1 LAST BODY_TYPE PLUMBING
J 2
(-7775 3775);
DISPLAY 0.872340 (-7775 3775);
PAINT GREEN (-7775 3775);
DISPLAY INVISIBLE (-7775 3775);
FORCEPROP 1 LAST HDL_TAP TRUE
J 2
(-8100 3600);
DISPLAY 0.872340 (-8100 3600);
DISPLAY INVISIBLE (-8100 3600);
FORCEPROP 1 LAST PATH I192
J 2
(-7773 3725);
DISPLAY 0.872340 (-7773 3725);
PAINT GREEN (-7773 3725);
DISPLAY INVISIBLE (-7773 3725);
FORCEADD TAP..1
R 2
(-7775 3675);
FORCEPROP 3 LASTPIN (-7725 3675) SIG_NAME M_F_CPU0_SB_CB<3>
J 0
(-7715 3685);
DISPLAY 0.659574 (-7715 3685);
PAINT MONO (-7715 3685);
DISPLAY INVISIBLE (-7715 3685);
FORCEPROP 1 LASTPIN (-7725 3675) BN 3
J 2
(-7713 3683);
DISPLAY 0.489362 (-7713 3683);
PAINT GREEN (-7713 3683);
FORCEPROP 2 LAST CDS_LIB mstr_standard
J 0
(-7775 3675);
DISPLAY 0.723404 (-7775 3675);
PAINT MONO (-7775 3675);
DISPLAY INVISIBLE (-7775 3675);
FORCEPROP 1 LAST BODY_TYPE PLUMBING
J 2
(-7775 3725);
DISPLAY 0.872340 (-7775 3725);
PAINT GREEN (-7775 3725);
DISPLAY INVISIBLE (-7775 3725);
FORCEPROP 1 LAST HDL_TAP TRUE
J 2
(-8100 3550);
DISPLAY 0.872340 (-8100 3550);
DISPLAY INVISIBLE (-8100 3550);
FORCEPROP 1 LAST PATH I193
J 2
(-7773 3675);
DISPLAY 0.872340 (-7773 3675);
PAINT GREEN (-7773 3675);
DISPLAY INVISIBLE (-7773 3675);
FORCEADD TAP..1
R 2
(-7775 3775);
FORCEPROP 3 LASTPIN (-7725 3775) SIG_NAME M_F_CPU0_SB_CB<5>
J 0
(-7715 3785);
DISPLAY 0.659574 (-7715 3785);
PAINT MONO (-7715 3785);
DISPLAY INVISIBLE (-7715 3785);
FORCEPROP 1 LASTPIN (-7725 3775) BN 5
J 2
(-7713 3783);
DISPLAY 0.489362 (-7713 3783);
PAINT GREEN (-7713 3783);
FORCEPROP 2 LAST CDS_LIB mstr_standard
J 0
(-7775 3775);
DISPLAY 0.723404 (-7775 3775);
PAINT MONO (-7775 3775);
DISPLAY INVISIBLE (-7775 3775);
FORCEPROP 1 LAST BODY_TYPE PLUMBING
J 2
(-7775 3825);
DISPLAY 0.872340 (-7775 3825);
PAINT GREEN (-7775 3825);
DISPLAY INVISIBLE (-7775 3825);
FORCEPROP 1 LAST HDL_TAP TRUE
J 2
(-8100 3650);
DISPLAY 0.872340 (-8100 3650);
DISPLAY INVISIBLE (-8100 3650);
FORCEPROP 1 LAST PATH I194
J 2
(-7773 3775);
DISPLAY 0.872340 (-7773 3775);
PAINT GREEN (-7773 3775);
DISPLAY INVISIBLE (-7773 3775);
FORCEADD TAP..1
R 2
(-7775 3825);
FORCEPROP 3 LASTPIN (-7725 3825) SIG_NAME M_F_CPU0_SB_CB<6>
J 0
(-7715 3835);
DISPLAY 0.659574 (-7715 3835);
PAINT MONO (-7715 3835);
DISPLAY INVISIBLE (-7715 3835);
FORCEPROP 1 LASTPIN (-7725 3825) BN 6
J 2
(-7713 3833);
DISPLAY 0.489362 (-7713 3833);
PAINT GREEN (-7713 3833);
FORCEPROP 2 LAST CDS_LIB mstr_standard
J 0
(-7775 3825);
DISPLAY 0.723404 (-7775 3825);
PAINT MONO (-7775 3825);
DISPLAY INVISIBLE (-7775 3825);
FORCEPROP 1 LAST BODY_TYPE PLUMBING
J 2
(-7775 3875);
DISPLAY 0.872340 (-7775 3875);
PAINT GREEN (-7775 3875);
DISPLAY INVISIBLE (-7775 3875);
FORCEPROP 1 LAST HDL_TAP TRUE
J 2
(-8100 3700);
DISPLAY 0.872340 (-8100 3700);
DISPLAY INVISIBLE (-8100 3700);
FORCEPROP 1 LAST PATH I195
J 2
(-7773 3825);
DISPLAY 0.872340 (-7773 3825);
PAINT GREEN (-7773 3825);
DISPLAY INVISIBLE (-7773 3825);
FORCEADD TAP..1
R 2
(-7775 3875);
FORCEPROP 3 LASTPIN (-7725 3875) SIG_NAME M_F_CPU0_SB_CB<7>
J 0
(-7715 3885);
DISPLAY 0.659574 (-7715 3885);
PAINT MONO (-7715 3885);
DISPLAY INVISIBLE (-7715 3885);
FORCEPROP 1 LASTPIN (-7725 3875) BN 7
J 2
(-7713 3883);
DISPLAY 0.489362 (-7713 3883);
PAINT GREEN (-7713 3883);
FORCEPROP 2 LAST CDS_LIB mstr_standard
J 0
(-7775 3875);
DISPLAY 0.723404 (-7775 3875);
PAINT MONO (-7775 3875);
DISPLAY INVISIBLE (-7775 3875);
FORCEPROP 1 LAST BODY_TYPE PLUMBING
J 2
(-7775 3925);
DISPLAY 0.872340 (-7775 3925);
PAINT GREEN (-7775 3925);
DISPLAY INVISIBLE (-7775 3925);
FORCEPROP 1 LAST HDL_TAP TRUE
J 2
(-8100 3750);
DISPLAY 0.872340 (-8100 3750);
DISPLAY INVISIBLE (-8100 3750);
FORCEPROP 1 LAST PATH I196
J 2
(-7773 3875);
DISPLAY 0.872340 (-7773 3875);
PAINT GREEN (-7773 3875);
DISPLAY INVISIBLE (-7773 3875);
FORCEADD TAP..1
R 2
(-7775 3975);
FORCEPROP 3 LASTPIN (-7725 3975) SIG_NAME M_F_CPU0_SA_CB<0>
J 0
(-7715 3985);
DISPLAY 0.659574 (-7715 3985);
PAINT MONO (-7715 3985);
DISPLAY INVISIBLE (-7715 3985);
FORCEPROP 1 LASTPIN (-7725 3975) BN 0
J 2
(-7713 3983);
DISPLAY 0.489362 (-7713 3983);
PAINT GREEN (-7713 3983);
FORCEPROP 2 LAST CDS_LIB mstr_standard
J 0
(-7775 3975);
DISPLAY 0.723404 (-7775 3975);
PAINT MONO (-7775 3975);
DISPLAY INVISIBLE (-7775 3975);
FORCEPROP 1 LAST BODY_TYPE PLUMBING
J 2
(-7775 4025);
DISPLAY 0.872340 (-7775 4025);
PAINT GREEN (-7775 4025);
DISPLAY INVISIBLE (-7775 4025);
FORCEPROP 1 LAST HDL_TAP TRUE
J 2
(-8100 3850);
DISPLAY 0.872340 (-8100 3850);
DISPLAY INVISIBLE (-8100 3850);
FORCEPROP 1 LAST PATH I197
J 2
(-7773 3975);
DISPLAY 0.872340 (-7773 3975);
PAINT GREEN (-7773 3975);
DISPLAY INVISIBLE (-7773 3975);
FORCEADD TAP..1
R 2
(-7775 4025);
FORCEPROP 3 LASTPIN (-7725 4025) SIG_NAME M_F_CPU0_SA_CB<1>
J 0
(-7715 4035);
DISPLAY 0.659574 (-7715 4035);
PAINT MONO (-7715 4035);
DISPLAY INVISIBLE (-7715 4035);
FORCEPROP 1 LASTPIN (-7725 4025) BN 1
J 2
(-7713 4033);
DISPLAY 0.489362 (-7713 4033);
PAINT GREEN (-7713 4033);
FORCEPROP 2 LAST CDS_LIB mstr_standard
J 0
(-7775 4025);
DISPLAY 0.723404 (-7775 4025);
PAINT MONO (-7775 4025);
DISPLAY INVISIBLE (-7775 4025);
FORCEPROP 1 LAST BODY_TYPE PLUMBING
J 2
(-7775 4075);
DISPLAY 0.872340 (-7775 4075);
PAINT GREEN (-7775 4075);
DISPLAY INVISIBLE (-7775 4075);
FORCEPROP 1 LAST HDL_TAP TRUE
J 2
(-8100 3900);
DISPLAY 0.872340 (-8100 3900);
DISPLAY INVISIBLE (-8100 3900);
FORCEPROP 1 LAST PATH I198
J 2
(-7773 4025);
DISPLAY 0.872340 (-7773 4025);
PAINT GREEN (-7773 4025);
DISPLAY INVISIBLE (-7773 4025);
FORCEADD TAP..1
R 2
(-7775 4075);
FORCEPROP 3 LASTPIN (-7725 4075) SIG_NAME M_F_CPU0_SA_CB<2>
J 0
(-7715 4085);
DISPLAY 0.659574 (-7715 4085);
PAINT MONO (-7715 4085);
DISPLAY INVISIBLE (-7715 4085);
FORCEPROP 1 LASTPIN (-7725 4075) BN 2
J 2
(-7713 4083);
DISPLAY 0.489362 (-7713 4083);
PAINT GREEN (-7713 4083);
FORCEPROP 2 LAST CDS_LIB mstr_standard
J 0
(-7775 4075);
DISPLAY 0.723404 (-7775 4075);
PAINT MONO (-7775 4075);
DISPLAY INVISIBLE (-7775 4075);
FORCEPROP 1 LAST BODY_TYPE PLUMBING
J 2
(-7775 4125);
DISPLAY 0.872340 (-7775 4125);
PAINT GREEN (-7775 4125);
DISPLAY INVISIBLE (-7775 4125);
FORCEPROP 1 LAST HDL_TAP TRUE
J 2
(-8100 3950);
DISPLAY 0.872340 (-8100 3950);
DISPLAY INVISIBLE (-8100 3950);
FORCEPROP 1 LAST PATH I199
J 2
(-7773 4075);
DISPLAY 0.872340 (-7773 4075);
PAINT GREEN (-7773 4075);
DISPLAY INVISIBLE (-7773 4075);
FORCEADD TAP..1
R 2
(-7775 4125);
FORCEPROP 3 LASTPIN (-7725 4125) SIG_NAME M_F_CPU0_SA_CB<3>
J 0
(-7715 4135);
DISPLAY 0.659574 (-7715 4135);
PAINT MONO (-7715 4135);
DISPLAY INVISIBLE (-7715 4135);
FORCEPROP 1 LASTPIN (-7725 4125) BN 3
J 2
(-7713 4133);
DISPLAY 0.489362 (-7713 4133);
PAINT GREEN (-7713 4133);
FORCEPROP 2 LAST CDS_LIB mstr_standard
J 0
(-7775 4125);
DISPLAY 0.723404 (-7775 4125);
PAINT MONO (-7775 4125);
DISPLAY INVISIBLE (-7775 4125);
FORCEPROP 1 LAST BODY_TYPE PLUMBING
J 2
(-7775 4175);
DISPLAY 0.872340 (-7775 4175);
PAINT GREEN (-7775 4175);
DISPLAY INVISIBLE (-7775 4175);
FORCEPROP 1 LAST HDL_TAP TRUE
J 2
(-8100 4000);
DISPLAY 0.872340 (-8100 4000);
DISPLAY INVISIBLE (-8100 4000);
FORCEPROP 1 LAST PATH I200
J 2
(-7773 4125);
DISPLAY 0.872340 (-7773 4125);
PAINT GREEN (-7773 4125);
DISPLAY INVISIBLE (-7773 4125);
FORCEADD TAP..1
R 2
(-7775 4225);
FORCEPROP 3 LASTPIN (-7725 4225) SIG_NAME M_F_CPU0_SA_CB<5>
J 0
(-7715 4235);
DISPLAY 0.659574 (-7715 4235);
PAINT MONO (-7715 4235);
DISPLAY INVISIBLE (-7715 4235);
FORCEPROP 1 LASTPIN (-7725 4225) BN 5
J 2
(-7713 4233);
DISPLAY 0.489362 (-7713 4233);
PAINT GREEN (-7713 4233);
FORCEPROP 2 LAST CDS_LIB mstr_standard
J 0
(-7775 4225);
DISPLAY 0.723404 (-7775 4225);
PAINT MONO (-7775 4225);
DISPLAY INVISIBLE (-7775 4225);
FORCEPROP 1 LAST BODY_TYPE PLUMBING
J 2
(-7775 4275);
DISPLAY 0.872340 (-7775 4275);
PAINT GREEN (-7775 4275);
DISPLAY INVISIBLE (-7775 4275);
FORCEPROP 1 LAST HDL_TAP TRUE
J 2
(-8100 4100);
DISPLAY 0.872340 (-8100 4100);
DISPLAY INVISIBLE (-8100 4100);
FORCEPROP 1 LAST PATH I201
J 2
(-7773 4225);
DISPLAY 0.872340 (-7773 4225);
PAINT GREEN (-7773 4225);
DISPLAY INVISIBLE (-7773 4225);
FORCEADD TAP..1
R 2
(-7775 4175);
FORCEPROP 3 LASTPIN (-7725 4175) SIG_NAME M_F_CPU0_SA_CB<4>
J 0
(-7715 4185);
DISPLAY 0.659574 (-7715 4185);
PAINT MONO (-7715 4185);
DISPLAY INVISIBLE (-7715 4185);
FORCEPROP 1 LASTPIN (-7725 4175) BN 4
J 2
(-7713 4183);
DISPLAY 0.489362 (-7713 4183);
PAINT GREEN (-7713 4183);
FORCEPROP 2 LAST CDS_LIB mstr_standard
J 0
(-7775 4175);
DISPLAY 0.723404 (-7775 4175);
PAINT MONO (-7775 4175);
DISPLAY INVISIBLE (-7775 4175);
FORCEPROP 1 LAST BODY_TYPE PLUMBING
J 2
(-7775 4225);
DISPLAY 0.872340 (-7775 4225);
PAINT GREEN (-7775 4225);
DISPLAY INVISIBLE (-7775 4225);
FORCEPROP 1 LAST HDL_TAP TRUE
J 2
(-8100 4050);
DISPLAY 0.872340 (-8100 4050);
DISPLAY INVISIBLE (-8100 4050);
FORCEPROP 1 LAST PATH I202
J 2
(-7773 4175);
DISPLAY 0.872340 (-7773 4175);
PAINT GREEN (-7773 4175);
DISPLAY INVISIBLE (-7773 4175);
FORCEADD TAP..1
R 2
(-7775 4325);
FORCEPROP 3 LASTPIN (-7725 4325) SIG_NAME M_F_CPU0_SA_CB<7>
J 0
(-7715 4335);
DISPLAY 0.659574 (-7715 4335);
PAINT MONO (-7715 4335);
DISPLAY INVISIBLE (-7715 4335);
FORCEPROP 1 LASTPIN (-7725 4325) BN 7
J 2
(-7713 4333);
DISPLAY 0.489362 (-7713 4333);
PAINT GREEN (-7713 4333);
FORCEPROP 2 LAST CDS_LIB mstr_standard
J 0
(-7775 4325);
DISPLAY 0.723404 (-7775 4325);
PAINT MONO (-7775 4325);
DISPLAY INVISIBLE (-7775 4325);
FORCEPROP 1 LAST BODY_TYPE PLUMBING
J 2
(-7775 4375);
DISPLAY 0.872340 (-7775 4375);
PAINT GREEN (-7775 4375);
DISPLAY INVISIBLE (-7775 4375);
FORCEPROP 1 LAST HDL_TAP TRUE
J 2
(-8100 4200);
DISPLAY 0.872340 (-8100 4200);
DISPLAY INVISIBLE (-8100 4200);
FORCEPROP 1 LAST PATH I203
J 2
(-7773 4325);
DISPLAY 0.872340 (-7773 4325);
PAINT GREEN (-7773 4325);
DISPLAY INVISIBLE (-7773 4325);
FORCEADD TAP..1
R 2
(-7775 4275);
FORCEPROP 3 LASTPIN (-7725 4275) SIG_NAME M_F_CPU0_SA_CB<6>
J 0
(-7715 4285);
DISPLAY 0.659574 (-7715 4285);
PAINT MONO (-7715 4285);
DISPLAY INVISIBLE (-7715 4285);
FORCEPROP 1 LASTPIN (-7725 4275) BN 6
J 2
(-7713 4283);
DISPLAY 0.489362 (-7713 4283);
PAINT GREEN (-7713 4283);
FORCEPROP 2 LAST CDS_LIB mstr_standard
J 0
(-7775 4275);
DISPLAY 0.723404 (-7775 4275);
PAINT MONO (-7775 4275);
DISPLAY INVISIBLE (-7775 4275);
FORCEPROP 1 LAST BODY_TYPE PLUMBING
J 2
(-7775 4325);
DISPLAY 0.872340 (-7775 4325);
PAINT GREEN (-7775 4325);
DISPLAY INVISIBLE (-7775 4325);
FORCEPROP 1 LAST HDL_TAP TRUE
J 2
(-8100 4150);
DISPLAY 0.872340 (-8100 4150);
DISPLAY INVISIBLE (-8100 4150);
FORCEPROP 1 LAST PATH I204
J 2
(-7773 4275);
DISPLAY 0.872340 (-7773 4275);
PAINT GREEN (-7773 4275);
DISPLAY INVISIBLE (-7773 4275);
FORCEADD TAP..1
R 2
(-7775 5025);
FORCEPROP 3 LASTPIN (-7725 5025) SIG_NAME M_F_CPU0_SB_CA<0>
J 0
(-7715 5035);
DISPLAY 0.659574 (-7715 5035);
PAINT MONO (-7715 5035);
DISPLAY INVISIBLE (-7715 5035);
FORCEPROP 1 LASTPIN (-7725 5025) BN 0
J 2
(-7713 5033);
DISPLAY 0.489362 (-7713 5033);
PAINT GREEN (-7713 5033);
FORCEPROP 2 LAST CDS_LIB mstr_standard
J 0
(-7775 5025);
DISPLAY 0.723404 (-7775 5025);
PAINT MONO (-7775 5025);
DISPLAY INVISIBLE (-7775 5025);
FORCEPROP 1 LAST BODY_TYPE PLUMBING
J 2
(-7775 5075);
DISPLAY 0.872340 (-7775 5075);
PAINT GREEN (-7775 5075);
DISPLAY INVISIBLE (-7775 5075);
FORCEPROP 1 LAST HDL_TAP TRUE
J 2
(-8100 4900);
DISPLAY 0.872340 (-8100 4900);
DISPLAY INVISIBLE (-8100 4900);
FORCEPROP 1 LAST PATH I205
J 2
(-7773 5025);
DISPLAY 0.872340 (-7773 5025);
PAINT GREEN (-7773 5025);
DISPLAY INVISIBLE (-7773 5025);
FORCEADD TAP..1
R 2
(-7775 5125);
FORCEPROP 3 LASTPIN (-7725 5125) SIG_NAME M_F_CPU0_SB_CA<2>
J 0
(-7715 5135);
DISPLAY 0.659574 (-7715 5135);
PAINT MONO (-7715 5135);
DISPLAY INVISIBLE (-7715 5135);
FORCEPROP 1 LASTPIN (-7725 5125) BN 2
J 2
(-7713 5133);
DISPLAY 0.489362 (-7713 5133);
PAINT GREEN (-7713 5133);
FORCEPROP 2 LAST CDS_LIB mstr_standard
J 0
(-7775 5125);
DISPLAY 0.723404 (-7775 5125);
PAINT MONO (-7775 5125);
DISPLAY INVISIBLE (-7775 5125);
FORCEPROP 1 LAST BODY_TYPE PLUMBING
J 2
(-7775 5175);
DISPLAY 0.872340 (-7775 5175);
PAINT GREEN (-7775 5175);
DISPLAY INVISIBLE (-7775 5175);
FORCEPROP 1 LAST HDL_TAP TRUE
J 2
(-8100 5000);
DISPLAY 0.872340 (-8100 5000);
DISPLAY INVISIBLE (-8100 5000);
FORCEPROP 1 LAST PATH I206
J 2
(-7773 5125);
DISPLAY 0.872340 (-7773 5125);
PAINT GREEN (-7773 5125);
DISPLAY INVISIBLE (-7773 5125);
FORCEADD TAP..1
R 2
(-7775 5075);
FORCEPROP 3 LASTPIN (-7725 5075) SIG_NAME M_F_CPU0_SB_CA<1>
J 0
(-7715 5085);
DISPLAY 0.659574 (-7715 5085);
PAINT MONO (-7715 5085);
DISPLAY INVISIBLE (-7715 5085);
FORCEPROP 1 LASTPIN (-7725 5075) BN 1
J 2
(-7713 5083);
DISPLAY 0.489362 (-7713 5083);
PAINT GREEN (-7713 5083);
FORCEPROP 2 LAST CDS_LIB mstr_standard
J 0
(-7775 5075);
DISPLAY 0.723404 (-7775 5075);
PAINT MONO (-7775 5075);
DISPLAY INVISIBLE (-7775 5075);
FORCEPROP 1 LAST BODY_TYPE PLUMBING
J 2
(-7775 5125);
DISPLAY 0.872340 (-7775 5125);
PAINT GREEN (-7775 5125);
DISPLAY INVISIBLE (-7775 5125);
FORCEPROP 1 LAST HDL_TAP TRUE
J 2
(-8100 4950);
DISPLAY 0.872340 (-8100 4950);
DISPLAY INVISIBLE (-8100 4950);
FORCEPROP 1 LAST PATH I207
J 2
(-7773 5075);
DISPLAY 0.872340 (-7773 5075);
PAINT GREEN (-7773 5075);
DISPLAY INVISIBLE (-7773 5075);
FORCEADD TAP..1
R 2
(-7775 5225);
FORCEPROP 3 LASTPIN (-7725 5225) SIG_NAME M_F_CPU0_SB_CA<4>
J 0
(-7715 5235);
DISPLAY 0.659574 (-7715 5235);
PAINT MONO (-7715 5235);
DISPLAY INVISIBLE (-7715 5235);
FORCEPROP 1 LASTPIN (-7725 5225) BN 4
J 2
(-7713 5233);
DISPLAY 0.489362 (-7713 5233);
PAINT GREEN (-7713 5233);
FORCEPROP 2 LAST CDS_LIB mstr_standard
J 0
(-7775 5225);
DISPLAY 0.723404 (-7775 5225);
PAINT MONO (-7775 5225);
DISPLAY INVISIBLE (-7775 5225);
FORCEPROP 1 LAST BODY_TYPE PLUMBING
J 2
(-7775 5275);
DISPLAY 0.872340 (-7775 5275);
PAINT GREEN (-7775 5275);
DISPLAY INVISIBLE (-7775 5275);
FORCEPROP 1 LAST HDL_TAP TRUE
J 2
(-8100 5100);
DISPLAY 0.872340 (-8100 5100);
DISPLAY INVISIBLE (-8100 5100);
FORCEPROP 1 LAST PATH I208
J 2
(-7773 5225);
DISPLAY 0.872340 (-7773 5225);
PAINT GREEN (-7773 5225);
DISPLAY INVISIBLE (-7773 5225);
FORCEADD TAP..1
R 2
(-7775 5175);
FORCEPROP 3 LASTPIN (-7725 5175) SIG_NAME M_F_CPU0_SB_CA<3>
J 0
(-7715 5185);
DISPLAY 0.659574 (-7715 5185);
PAINT MONO (-7715 5185);
DISPLAY INVISIBLE (-7715 5185);
FORCEPROP 1 LASTPIN (-7725 5175) BN 3
J 2
(-7713 5183);
DISPLAY 0.489362 (-7713 5183);
PAINT GREEN (-7713 5183);
FORCEPROP 2 LAST CDS_LIB mstr_standard
J 0
(-7775 5175);
DISPLAY 0.723404 (-7775 5175);
PAINT MONO (-7775 5175);
DISPLAY INVISIBLE (-7775 5175);
FORCEPROP 1 LAST BODY_TYPE PLUMBING
J 2
(-7775 5225);
DISPLAY 0.872340 (-7775 5225);
PAINT GREEN (-7775 5225);
DISPLAY INVISIBLE (-7775 5225);
FORCEPROP 1 LAST HDL_TAP TRUE
J 2
(-8100 5050);
DISPLAY 0.872340 (-8100 5050);
DISPLAY INVISIBLE (-8100 5050);
FORCEPROP 1 LAST PATH I209
J 2
(-7773 5175);
DISPLAY 0.872340 (-7773 5175);
PAINT GREEN (-7773 5175);
DISPLAY INVISIBLE (-7773 5175);
FORCEADD TAP..1
R 2
(-7775 5275);
FORCEPROP 3 LASTPIN (-7725 5275) SIG_NAME M_F_CPU0_SB_CA<5>
J 0
(-7715 5285);
DISPLAY 0.659574 (-7715 5285);
PAINT MONO (-7715 5285);
DISPLAY INVISIBLE (-7715 5285);
FORCEPROP 1 LASTPIN (-7725 5275) BN 5
J 2
(-7713 5283);
DISPLAY 0.489362 (-7713 5283);
PAINT GREEN (-7713 5283);
FORCEPROP 2 LAST CDS_LIB mstr_standard
J 0
(-7775 5275);
DISPLAY 0.723404 (-7775 5275);
PAINT MONO (-7775 5275);
DISPLAY INVISIBLE (-7775 5275);
FORCEPROP 1 LAST BODY_TYPE PLUMBING
J 2
(-7775 5325);
DISPLAY 0.872340 (-7775 5325);
PAINT GREEN (-7775 5325);
DISPLAY INVISIBLE (-7775 5325);
FORCEPROP 1 LAST HDL_TAP TRUE
J 2
(-8100 5150);
DISPLAY 0.872340 (-8100 5150);
DISPLAY INVISIBLE (-8100 5150);
FORCEPROP 1 LAST PATH I210
J 2
(-7773 5275);
DISPLAY 0.872340 (-7773 5275);
PAINT GREEN (-7773 5275);
DISPLAY INVISIBLE (-7773 5275);
FORCEADD TAP..1
R 2
(-7775 5325);
FORCEPROP 3 LASTPIN (-7725 5325) SIG_NAME M_F_CPU0_SB_CA<6>
J 0
(-7715 5335);
DISPLAY 0.659574 (-7715 5335);
PAINT MONO (-7715 5335);
DISPLAY INVISIBLE (-7715 5335);
FORCEPROP 1 LASTPIN (-7725 5325) BN 6
J 2
(-7713 5333);
DISPLAY 0.489362 (-7713 5333);
PAINT GREEN (-7713 5333);
FORCEPROP 2 LAST CDS_LIB mstr_standard
J 0
(-7775 5325);
DISPLAY 0.723404 (-7775 5325);
PAINT MONO (-7775 5325);
DISPLAY INVISIBLE (-7775 5325);
FORCEPROP 1 LAST BODY_TYPE PLUMBING
J 2
(-7775 5375);
DISPLAY 0.872340 (-7775 5375);
PAINT GREEN (-7775 5375);
DISPLAY INVISIBLE (-7775 5375);
FORCEPROP 1 LAST HDL_TAP TRUE
J 2
(-8100 5200);
DISPLAY 0.872340 (-8100 5200);
DISPLAY INVISIBLE (-8100 5200);
FORCEPROP 1 LAST PATH I211
J 2
(-7773 5325);
DISPLAY 0.872340 (-7773 5325);
PAINT GREEN (-7773 5325);
DISPLAY INVISIBLE (-7773 5325);
FORCEADD TAP..1
R 2
(-7775 5425);
FORCEPROP 3 LASTPIN (-7725 5425) SIG_NAME M_F_CPU0_SA_CA<0>
J 0
(-7715 5435);
DISPLAY 0.659574 (-7715 5435);
PAINT MONO (-7715 5435);
DISPLAY INVISIBLE (-7715 5435);
FORCEPROP 1 LASTPIN (-7725 5425) BN 0
J 2
(-7713 5433);
DISPLAY 0.489362 (-7713 5433);
PAINT GREEN (-7713 5433);
FORCEPROP 2 LAST CDS_LIB mstr_standard
J 0
(-7775 5425);
DISPLAY 0.723404 (-7775 5425);
PAINT MONO (-7775 5425);
DISPLAY INVISIBLE (-7775 5425);
FORCEPROP 1 LAST BODY_TYPE PLUMBING
J 2
(-7775 5475);
DISPLAY 0.872340 (-7775 5475);
PAINT GREEN (-7775 5475);
DISPLAY INVISIBLE (-7775 5475);
FORCEPROP 1 LAST HDL_TAP TRUE
J 2
(-8100 5300);
DISPLAY 0.872340 (-8100 5300);
DISPLAY INVISIBLE (-8100 5300);
FORCEPROP 1 LAST PATH I212
J 2
(-7773 5425);
DISPLAY 0.872340 (-7773 5425);
PAINT GREEN (-7773 5425);
DISPLAY INVISIBLE (-7773 5425);
FORCEADD TAP..1
R 2
(-7775 5475);
FORCEPROP 3 LASTPIN (-7725 5475) SIG_NAME M_F_CPU0_SA_CA<1>
J 0
(-7715 5485);
DISPLAY 0.659574 (-7715 5485);
PAINT MONO (-7715 5485);
DISPLAY INVISIBLE (-7715 5485);
FORCEPROP 1 LASTPIN (-7725 5475) BN 1
J 2
(-7713 5483);
DISPLAY 0.489362 (-7713 5483);
PAINT GREEN (-7713 5483);
FORCEPROP 2 LAST CDS_LIB mstr_standard
J 0
(-7775 5475);
DISPLAY 0.723404 (-7775 5475);
PAINT MONO (-7775 5475);
DISPLAY INVISIBLE (-7775 5475);
FORCEPROP 1 LAST BODY_TYPE PLUMBING
J 2
(-7775 5525);
DISPLAY 0.872340 (-7775 5525);
PAINT GREEN (-7775 5525);
DISPLAY INVISIBLE (-7775 5525);
FORCEPROP 1 LAST HDL_TAP TRUE
J 2
(-8100 5350);
DISPLAY 0.872340 (-8100 5350);
DISPLAY INVISIBLE (-8100 5350);
FORCEPROP 1 LAST PATH I213
J 2
(-7773 5475);
DISPLAY 0.872340 (-7773 5475);
PAINT GREEN (-7773 5475);
DISPLAY INVISIBLE (-7773 5475);
FORCEADD TAP..1
R 2
(-7775 5525);
FORCEPROP 3 LASTPIN (-7725 5525) SIG_NAME M_F_CPU0_SA_CA<2>
J 0
(-7715 5535);
DISPLAY 0.659574 (-7715 5535);
PAINT MONO (-7715 5535);
DISPLAY INVISIBLE (-7715 5535);
FORCEPROP 1 LASTPIN (-7725 5525) BN 2
J 2
(-7713 5533);
DISPLAY 0.489362 (-7713 5533);
PAINT GREEN (-7713 5533);
FORCEPROP 2 LAST CDS_LIB mstr_standard
J 0
(-7775 5525);
DISPLAY 0.723404 (-7775 5525);
PAINT MONO (-7775 5525);
DISPLAY INVISIBLE (-7775 5525);
FORCEPROP 1 LAST BODY_TYPE PLUMBING
J 2
(-7775 5575);
DISPLAY 0.872340 (-7775 5575);
PAINT GREEN (-7775 5575);
DISPLAY INVISIBLE (-7775 5575);
FORCEPROP 1 LAST HDL_TAP TRUE
J 2
(-8100 5400);
DISPLAY 0.872340 (-8100 5400);
DISPLAY INVISIBLE (-8100 5400);
FORCEPROP 1 LAST PATH I214
J 2
(-7773 5525);
DISPLAY 0.872340 (-7773 5525);
PAINT GREEN (-7773 5525);
DISPLAY INVISIBLE (-7773 5525);
FORCEADD TAP..1
R 2
(-7775 5625);
FORCEPROP 3 LASTPIN (-7725 5625) SIG_NAME M_F_CPU0_SA_CA<4>
J 0
(-7715 5635);
DISPLAY 0.659574 (-7715 5635);
PAINT MONO (-7715 5635);
DISPLAY INVISIBLE (-7715 5635);
FORCEPROP 1 LASTPIN (-7725 5625) BN 4
J 2
(-7713 5633);
DISPLAY 0.489362 (-7713 5633);
PAINT GREEN (-7713 5633);
FORCEPROP 2 LAST CDS_LIB mstr_standard
J 0
(-7775 5625);
DISPLAY 0.723404 (-7775 5625);
PAINT MONO (-7775 5625);
DISPLAY INVISIBLE (-7775 5625);
FORCEPROP 1 LAST BODY_TYPE PLUMBING
J 2
(-7775 5675);
DISPLAY 0.872340 (-7775 5675);
PAINT GREEN (-7775 5675);
DISPLAY INVISIBLE (-7775 5675);
FORCEPROP 1 LAST HDL_TAP TRUE
J 2
(-8100 5500);
DISPLAY 0.872340 (-8100 5500);
DISPLAY INVISIBLE (-8100 5500);
FORCEPROP 1 LAST PATH I215
J 2
(-7773 5625);
DISPLAY 0.872340 (-7773 5625);
PAINT GREEN (-7773 5625);
DISPLAY INVISIBLE (-7773 5625);
FORCEADD TAP..1
R 2
(-7775 5575);
FORCEPROP 3 LASTPIN (-7725 5575) SIG_NAME M_F_CPU0_SA_CA<3>
J 0
(-7715 5585);
DISPLAY 0.659574 (-7715 5585);
PAINT MONO (-7715 5585);
DISPLAY INVISIBLE (-7715 5585);
FORCEPROP 1 LASTPIN (-7725 5575) BN 3
J 2
(-7713 5583);
DISPLAY 0.489362 (-7713 5583);
PAINT GREEN (-7713 5583);
FORCEPROP 2 LAST CDS_LIB mstr_standard
J 0
(-7775 5575);
DISPLAY 0.723404 (-7775 5575);
PAINT MONO (-7775 5575);
DISPLAY INVISIBLE (-7775 5575);
FORCEPROP 1 LAST BODY_TYPE PLUMBING
J 2
(-7775 5625);
DISPLAY 0.872340 (-7775 5625);
PAINT GREEN (-7775 5625);
DISPLAY INVISIBLE (-7775 5625);
FORCEPROP 1 LAST HDL_TAP TRUE
J 2
(-8100 5450);
DISPLAY 0.872340 (-8100 5450);
DISPLAY INVISIBLE (-8100 5450);
FORCEPROP 1 LAST PATH I216
J 2
(-7773 5575);
DISPLAY 0.872340 (-7773 5575);
PAINT GREEN (-7773 5575);
DISPLAY INVISIBLE (-7773 5575);
FORCEADD TAP..1
R 2
(-7775 5675);
FORCEPROP 3 LASTPIN (-7725 5675) SIG_NAME M_F_CPU0_SA_CA<5>
J 0
(-7715 5685);
DISPLAY 0.659574 (-7715 5685);
PAINT MONO (-7715 5685);
DISPLAY INVISIBLE (-7715 5685);
FORCEPROP 1 LASTPIN (-7725 5675) BN 5
J 2
(-7713 5683);
DISPLAY 0.489362 (-7713 5683);
PAINT GREEN (-7713 5683);
FORCEPROP 2 LAST CDS_LIB mstr_standard
J 0
(-7775 5675);
DISPLAY 0.723404 (-7775 5675);
PAINT MONO (-7775 5675);
DISPLAY INVISIBLE (-7775 5675);
FORCEPROP 1 LAST BODY_TYPE PLUMBING
J 2
(-7775 5725);
DISPLAY 0.872340 (-7775 5725);
PAINT GREEN (-7775 5725);
DISPLAY INVISIBLE (-7775 5725);
FORCEPROP 1 LAST HDL_TAP TRUE
J 2
(-8100 5550);
DISPLAY 0.872340 (-8100 5550);
DISPLAY INVISIBLE (-8100 5550);
FORCEPROP 1 LAST PATH I217
J 2
(-7773 5675);
DISPLAY 0.872340 (-7773 5675);
PAINT GREEN (-7773 5675);
DISPLAY INVISIBLE (-7773 5675);
FORCEADD TAP..1
R 2
(-7775 5725);
FORCEPROP 3 LASTPIN (-7725 5725) SIG_NAME M_F_CPU0_SA_CA<6>
J 0
(-7715 5735);
DISPLAY 0.659574 (-7715 5735);
PAINT MONO (-7715 5735);
DISPLAY INVISIBLE (-7715 5735);
FORCEPROP 1 LASTPIN (-7725 5725) BN 6
J 2
(-7713 5733);
DISPLAY 0.489362 (-7713 5733);
PAINT GREEN (-7713 5733);
FORCEPROP 2 LAST CDS_LIB mstr_standard
J 0
(-7775 5725);
DISPLAY 0.723404 (-7775 5725);
PAINT MONO (-7775 5725);
DISPLAY INVISIBLE (-7775 5725);
FORCEPROP 1 LAST BODY_TYPE PLUMBING
J 2
(-7775 5775);
DISPLAY 0.872340 (-7775 5775);
PAINT GREEN (-7775 5775);
DISPLAY INVISIBLE (-7775 5775);
FORCEPROP 1 LAST HDL_TAP TRUE
J 2
(-8100 5600);
DISPLAY 0.872340 (-8100 5600);
DISPLAY INVISIBLE (-8100 5600);
FORCEPROP 1 LAST PATH I218
J 2
(-7773 5725);
DISPLAY 0.872340 (-7773 5725);
PAINT GREEN (-7773 5725);
DISPLAY INVISIBLE (-7773 5725);
FORCEADD TAP..1
(-6075 5625);
FORCEPROP 3 LASTPIN (-6125 5625) SIG_NAME M_F_CPU0_SA_DQ<29>
J 0
(-6115 5635);
DISPLAY 0.659574 (-6115 5635);
PAINT MONO (-6115 5635);
DISPLAY INVISIBLE (-6115 5635);
FORCEPROP 1 LASTPIN (-6125 5625) BN 29
J 0
(-6137 5633);
DISPLAY 0.489362 (-6137 5633);
PAINT GREEN (-6137 5633);
FORCEPROP 2 LAST CDS_LIB mstr_standard
J 0
(-6075 5625);
DISPLAY 0.723404 (-6075 5625);
PAINT MONO (-6075 5625);
DISPLAY INVISIBLE (-6075 5625);
FORCEPROP 1 LAST BODY_TYPE PLUMBING
J 0
(-6075 5675);
DISPLAY 0.872340 (-6075 5675);
PAINT GREEN (-6075 5675);
DISPLAY INVISIBLE (-6075 5675);
FORCEPROP 1 LAST HDL_TAP TRUE
J 0
(-5750 5500);
DISPLAY 0.872340 (-5750 5500);
DISPLAY INVISIBLE (-5750 5500);
FORCEPROP 1 LAST PATH I219
J 0
(-6077 5625);
DISPLAY 0.872340 (-6077 5625);
PAINT GREEN (-6077 5625);
DISPLAY INVISIBLE (-6077 5625);
FORCEADD TAP..1
(-6075 5675);
FORCEPROP 3 LASTPIN (-6125 5675) SIG_NAME M_F_CPU0_SA_DQ<30>
J 0
(-6115 5685);
DISPLAY 0.659574 (-6115 5685);
PAINT MONO (-6115 5685);
DISPLAY INVISIBLE (-6115 5685);
FORCEPROP 1 LASTPIN (-6125 5675) BN 30
J 0
(-6137 5683);
DISPLAY 0.489362 (-6137 5683);
PAINT GREEN (-6137 5683);
FORCEPROP 2 LAST CDS_LIB mstr_standard
J 0
(-6075 5675);
DISPLAY 0.723404 (-6075 5675);
PAINT MONO (-6075 5675);
DISPLAY INVISIBLE (-6075 5675);
FORCEPROP 1 LAST BODY_TYPE PLUMBING
J 0
(-6075 5725);
DISPLAY 0.872340 (-6075 5725);
PAINT GREEN (-6075 5725);
DISPLAY INVISIBLE (-6075 5725);
FORCEPROP 1 LAST HDL_TAP TRUE
J 0
(-5750 5550);
DISPLAY 0.872340 (-5750 5550);
DISPLAY INVISIBLE (-5750 5550);
FORCEPROP 1 LAST PATH I220
J 0
(-6077 5675);
DISPLAY 0.872340 (-6077 5675);
PAINT GREEN (-6077 5675);
DISPLAY INVISIBLE (-6077 5675);
FORCEADD TAP..1
(-6075 5575);
FORCEPROP 3 LASTPIN (-6125 5575) SIG_NAME M_F_CPU0_SA_DQ<28>
J 0
(-6115 5585);
DISPLAY 0.659574 (-6115 5585);
PAINT MONO (-6115 5585);
DISPLAY INVISIBLE (-6115 5585);
FORCEPROP 1 LASTPIN (-6125 5575) BN 28
J 0
(-6137 5583);
DISPLAY 0.489362 (-6137 5583);
PAINT GREEN (-6137 5583);
FORCEPROP 2 LAST CDS_LIB mstr_standard
J 0
(-6075 5575);
DISPLAY 0.723404 (-6075 5575);
PAINT MONO (-6075 5575);
DISPLAY INVISIBLE (-6075 5575);
FORCEPROP 1 LAST BODY_TYPE PLUMBING
J 0
(-6075 5625);
DISPLAY 0.872340 (-6075 5625);
PAINT GREEN (-6075 5625);
DISPLAY INVISIBLE (-6075 5625);
FORCEPROP 1 LAST HDL_TAP TRUE
J 0
(-5750 5450);
DISPLAY 0.872340 (-5750 5450);
DISPLAY INVISIBLE (-5750 5450);
FORCEPROP 1 LAST PATH I221
J 0
(-6077 5575);
DISPLAY 0.872340 (-6077 5575);
PAINT GREEN (-6077 5575);
DISPLAY INVISIBLE (-6077 5575);
FORCEADD TAP..1
(-6075 5525);
FORCEPROP 3 LASTPIN (-6125 5525) SIG_NAME M_F_CPU0_SA_DQ<27>
J 0
(-6115 5535);
DISPLAY 0.659574 (-6115 5535);
PAINT MONO (-6115 5535);
DISPLAY INVISIBLE (-6115 5535);
FORCEPROP 1 LASTPIN (-6125 5525) BN 27
J 0
(-6137 5533);
DISPLAY 0.489362 (-6137 5533);
PAINT GREEN (-6137 5533);
FORCEPROP 2 LAST CDS_LIB mstr_standard
J 0
(-6075 5525);
DISPLAY 0.723404 (-6075 5525);
PAINT MONO (-6075 5525);
DISPLAY INVISIBLE (-6075 5525);
FORCEPROP 1 LAST BODY_TYPE PLUMBING
J 0
(-6075 5575);
DISPLAY 0.872340 (-6075 5575);
PAINT GREEN (-6075 5575);
DISPLAY INVISIBLE (-6075 5575);
FORCEPROP 1 LAST HDL_TAP TRUE
J 0
(-5750 5400);
DISPLAY 0.872340 (-5750 5400);
DISPLAY INVISIBLE (-5750 5400);
FORCEPROP 1 LAST PATH I222
J 0
(-6077 5525);
DISPLAY 0.872340 (-6077 5525);
PAINT GREEN (-6077 5525);
DISPLAY INVISIBLE (-6077 5525);
FORCEADD TAP..1
(-6075 5725);
FORCEPROP 3 LASTPIN (-6125 5725) SIG_NAME M_F_CPU0_SA_DQ<31>
J 0
(-6115 5735);
DISPLAY 0.659574 (-6115 5735);
PAINT MONO (-6115 5735);
DISPLAY INVISIBLE (-6115 5735);
FORCEPROP 1 LASTPIN (-6125 5725) BN 31
J 0
(-6137 5733);
DISPLAY 0.489362 (-6137 5733);
PAINT GREEN (-6137 5733);
FORCEPROP 2 LAST CDS_LIB mstr_standard
J 0
(-6075 5725);
DISPLAY 0.723404 (-6075 5725);
PAINT MONO (-6075 5725);
DISPLAY INVISIBLE (-6075 5725);
FORCEPROP 1 LAST BODY_TYPE PLUMBING
J 0
(-6075 5775);
DISPLAY 0.872340 (-6075 5775);
PAINT GREEN (-6075 5775);
DISPLAY INVISIBLE (-6075 5775);
FORCEPROP 1 LAST HDL_TAP TRUE
J 0
(-5750 5600);
DISPLAY 0.872340 (-5750 5600);
DISPLAY INVISIBLE (-5750 5600);
FORCEPROP 1 LAST PATH I223
J 0
(-6077 5725);
DISPLAY 0.872340 (-6077 5725);
PAINT GREEN (-6077 5725);
DISPLAY INVISIBLE (-6077 5725);
FORCEADD TAP..1
(-6075 5475);
FORCEPROP 3 LASTPIN (-6125 5475) SIG_NAME M_F_CPU0_SA_DQ<26>
J 0
(-6115 5485);
DISPLAY 0.659574 (-6115 5485);
PAINT MONO (-6115 5485);
DISPLAY INVISIBLE (-6115 5485);
FORCEPROP 1 LASTPIN (-6125 5475) BN 26
J 0
(-6137 5483);
DISPLAY 0.489362 (-6137 5483);
PAINT GREEN (-6137 5483);
FORCEPROP 2 LAST CDS_LIB mstr_standard
J 0
(-6075 5475);
DISPLAY 0.723404 (-6075 5475);
PAINT MONO (-6075 5475);
DISPLAY INVISIBLE (-6075 5475);
FORCEPROP 1 LAST BODY_TYPE PLUMBING
J 0
(-6075 5525);
DISPLAY 0.872340 (-6075 5525);
PAINT GREEN (-6075 5525);
DISPLAY INVISIBLE (-6075 5525);
FORCEPROP 1 LAST HDL_TAP TRUE
J 0
(-5750 5350);
DISPLAY 0.872340 (-5750 5350);
DISPLAY INVISIBLE (-5750 5350);
FORCEPROP 1 LAST PATH I224
J 0
(-6077 5475);
DISPLAY 0.872340 (-6077 5475);
PAINT GREEN (-6077 5475);
DISPLAY INVISIBLE (-6077 5475);
FORCEADD TAP..1
(-6075 5425);
FORCEPROP 3 LASTPIN (-6125 5425) SIG_NAME M_F_CPU0_SA_DQ<25>
J 0
(-6115 5435);
DISPLAY 0.659574 (-6115 5435);
PAINT MONO (-6115 5435);
DISPLAY INVISIBLE (-6115 5435);
FORCEPROP 1 LASTPIN (-6125 5425) BN 25
J 0
(-6137 5433);
DISPLAY 0.489362 (-6137 5433);
PAINT GREEN (-6137 5433);
FORCEPROP 2 LAST CDS_LIB mstr_standard
J 0
(-6075 5425);
DISPLAY 0.723404 (-6075 5425);
PAINT MONO (-6075 5425);
DISPLAY INVISIBLE (-6075 5425);
FORCEPROP 1 LAST BODY_TYPE PLUMBING
J 0
(-6075 5475);
DISPLAY 0.872340 (-6075 5475);
PAINT GREEN (-6075 5475);
DISPLAY INVISIBLE (-6075 5475);
FORCEPROP 1 LAST HDL_TAP TRUE
J 0
(-5750 5300);
DISPLAY 0.872340 (-5750 5300);
DISPLAY INVISIBLE (-5750 5300);
FORCEPROP 1 LAST PATH I225
J 0
(-6077 5425);
DISPLAY 0.872340 (-6077 5425);
PAINT GREEN (-6077 5425);
DISPLAY INVISIBLE (-6077 5425);
FORCEADD TAP..1
(-6075 5375);
FORCEPROP 3 LASTPIN (-6125 5375) SIG_NAME M_F_CPU0_SA_DQ<24>
J 0
(-6115 5385);
DISPLAY 0.659574 (-6115 5385);
PAINT MONO (-6115 5385);
DISPLAY INVISIBLE (-6115 5385);
FORCEPROP 1 LASTPIN (-6125 5375) BN 24
J 0
(-6137 5383);
DISPLAY 0.489362 (-6137 5383);
PAINT GREEN (-6137 5383);
FORCEPROP 2 LAST CDS_LIB mstr_standard
J 0
(-6075 5375);
DISPLAY 0.723404 (-6075 5375);
PAINT MONO (-6075 5375);
DISPLAY INVISIBLE (-6075 5375);
FORCEPROP 1 LAST BODY_TYPE PLUMBING
J 0
(-6075 5425);
DISPLAY 0.872340 (-6075 5425);
PAINT GREEN (-6075 5425);
DISPLAY INVISIBLE (-6075 5425);
FORCEPROP 1 LAST HDL_TAP TRUE
J 0
(-5750 5250);
DISPLAY 0.872340 (-5750 5250);
DISPLAY INVISIBLE (-5750 5250);
FORCEPROP 1 LAST PATH I226
J 0
(-6077 5375);
DISPLAY 0.872340 (-6077 5375);
PAINT GREEN (-6077 5375);
DISPLAY INVISIBLE (-6077 5375);
FORCEADD TAP..1
(-6075 5275);
FORCEPROP 3 LASTPIN (-6125 5275) SIG_NAME M_F_CPU0_SA_DQ<22>
J 0
(-6115 5285);
DISPLAY 0.659574 (-6115 5285);
PAINT MONO (-6115 5285);
DISPLAY INVISIBLE (-6115 5285);
FORCEPROP 1 LASTPIN (-6125 5275) BN 22
J 0
(-6137 5283);
DISPLAY 0.489362 (-6137 5283);
PAINT GREEN (-6137 5283);
FORCEPROP 2 LAST CDS_LIB mstr_standard
J 0
(-6075 5275);
DISPLAY 0.723404 (-6075 5275);
PAINT MONO (-6075 5275);
DISPLAY INVISIBLE (-6075 5275);
FORCEPROP 1 LAST BODY_TYPE PLUMBING
J 0
(-6075 5325);
DISPLAY 0.872340 (-6075 5325);
PAINT GREEN (-6075 5325);
DISPLAY INVISIBLE (-6075 5325);
FORCEPROP 1 LAST HDL_TAP TRUE
J 0
(-5750 5150);
DISPLAY 0.872340 (-5750 5150);
DISPLAY INVISIBLE (-5750 5150);
FORCEPROP 1 LAST PATH I227
J 0
(-6077 5275);
DISPLAY 0.872340 (-6077 5275);
PAINT GREEN (-6077 5275);
DISPLAY INVISIBLE (-6077 5275);
FORCEADD TAP..1
(-6075 5225);
FORCEPROP 3 LASTPIN (-6125 5225) SIG_NAME M_F_CPU0_SA_DQ<21>
J 0
(-6115 5235);
DISPLAY 0.659574 (-6115 5235);
PAINT MONO (-6115 5235);
DISPLAY INVISIBLE (-6115 5235);
FORCEPROP 1 LASTPIN (-6125 5225) BN 21
J 0
(-6137 5233);
DISPLAY 0.489362 (-6137 5233);
PAINT GREEN (-6137 5233);
FORCEPROP 2 LAST CDS_LIB mstr_standard
J 0
(-6075 5225);
DISPLAY 0.723404 (-6075 5225);
PAINT MONO (-6075 5225);
DISPLAY INVISIBLE (-6075 5225);
FORCEPROP 1 LAST BODY_TYPE PLUMBING
J 0
(-6075 5275);
DISPLAY 0.872340 (-6075 5275);
PAINT GREEN (-6075 5275);
DISPLAY INVISIBLE (-6075 5275);
FORCEPROP 1 LAST HDL_TAP TRUE
J 0
(-5750 5100);
DISPLAY 0.872340 (-5750 5100);
DISPLAY INVISIBLE (-5750 5100);
FORCEPROP 1 LAST PATH I228
J 0
(-6077 5225);
DISPLAY 0.872340 (-6077 5225);
PAINT GREEN (-6077 5225);
DISPLAY INVISIBLE (-6077 5225);
FORCEADD TAP..1
(-6075 5325);
FORCEPROP 3 LASTPIN (-6125 5325) SIG_NAME M_F_CPU0_SA_DQ<23>
J 0
(-6115 5335);
DISPLAY 0.659574 (-6115 5335);
PAINT MONO (-6115 5335);
DISPLAY INVISIBLE (-6115 5335);
FORCEPROP 1 LASTPIN (-6125 5325) BN 23
J 0
(-6137 5333);
DISPLAY 0.489362 (-6137 5333);
PAINT GREEN (-6137 5333);
FORCEPROP 2 LAST CDS_LIB mstr_standard
J 0
(-6075 5325);
DISPLAY 0.723404 (-6075 5325);
PAINT MONO (-6075 5325);
DISPLAY INVISIBLE (-6075 5325);
FORCEPROP 1 LAST BODY_TYPE PLUMBING
J 0
(-6075 5375);
DISPLAY 0.872340 (-6075 5375);
PAINT GREEN (-6075 5375);
DISPLAY INVISIBLE (-6075 5375);
FORCEPROP 1 LAST HDL_TAP TRUE
J 0
(-5750 5200);
DISPLAY 0.872340 (-5750 5200);
DISPLAY INVISIBLE (-5750 5200);
FORCEPROP 1 LAST PATH I229
J 0
(-6077 5325);
DISPLAY 0.872340 (-6077 5325);
PAINT GREEN (-6077 5325);
DISPLAY INVISIBLE (-6077 5325);
FORCEADD TAP..1
(-6075 5125);
FORCEPROP 3 LASTPIN (-6125 5125) SIG_NAME M_F_CPU0_SA_DQ<19>
J 0
(-6115 5135);
DISPLAY 0.659574 (-6115 5135);
PAINT MONO (-6115 5135);
DISPLAY INVISIBLE (-6115 5135);
FORCEPROP 1 LASTPIN (-6125 5125) BN 19
J 0
(-6137 5133);
DISPLAY 0.489362 (-6137 5133);
PAINT GREEN (-6137 5133);
FORCEPROP 2 LAST CDS_LIB mstr_standard
J 0
(-6075 5125);
DISPLAY 0.723404 (-6075 5125);
PAINT MONO (-6075 5125);
DISPLAY INVISIBLE (-6075 5125);
FORCEPROP 1 LAST BODY_TYPE PLUMBING
J 0
(-6075 5175);
DISPLAY 0.872340 (-6075 5175);
PAINT GREEN (-6075 5175);
DISPLAY INVISIBLE (-6075 5175);
FORCEPROP 1 LAST HDL_TAP TRUE
J 0
(-5750 5000);
DISPLAY 0.872340 (-5750 5000);
DISPLAY INVISIBLE (-5750 5000);
FORCEPROP 1 LAST PATH I230
J 0
(-6077 5125);
DISPLAY 0.872340 (-6077 5125);
PAINT GREEN (-6077 5125);
DISPLAY INVISIBLE (-6077 5125);
FORCEADD TAP..1
(-6075 5175);
FORCEPROP 3 LASTPIN (-6125 5175) SIG_NAME M_F_CPU0_SA_DQ<20>
J 0
(-6115 5185);
DISPLAY 0.659574 (-6115 5185);
PAINT MONO (-6115 5185);
DISPLAY INVISIBLE (-6115 5185);
FORCEPROP 1 LASTPIN (-6125 5175) BN 20
J 0
(-6137 5183);
DISPLAY 0.489362 (-6137 5183);
PAINT GREEN (-6137 5183);
FORCEPROP 2 LAST CDS_LIB mstr_standard
J 0
(-6075 5175);
DISPLAY 0.723404 (-6075 5175);
PAINT MONO (-6075 5175);
DISPLAY INVISIBLE (-6075 5175);
FORCEPROP 1 LAST BODY_TYPE PLUMBING
J 0
(-6075 5225);
DISPLAY 0.872340 (-6075 5225);
PAINT GREEN (-6075 5225);
DISPLAY INVISIBLE (-6075 5225);
FORCEPROP 1 LAST HDL_TAP TRUE
J 0
(-5750 5050);
DISPLAY 0.872340 (-5750 5050);
DISPLAY INVISIBLE (-5750 5050);
FORCEPROP 1 LAST PATH I231
J 0
(-6077 5175);
DISPLAY 0.872340 (-6077 5175);
PAINT GREEN (-6077 5175);
DISPLAY INVISIBLE (-6077 5175);
FORCEADD TAP..1
(-6075 4975);
FORCEPROP 3 LASTPIN (-6125 4975) SIG_NAME M_F_CPU0_SA_DQ<16>
J 0
(-6115 4985);
DISPLAY 0.659574 (-6115 4985);
PAINT MONO (-6115 4985);
DISPLAY INVISIBLE (-6115 4985);
FORCEPROP 1 LASTPIN (-6125 4975) BN 16
J 0
(-6137 4983);
DISPLAY 0.489362 (-6137 4983);
PAINT GREEN (-6137 4983);
FORCEPROP 2 LAST CDS_LIB mstr_standard
J 0
(-6075 4975);
DISPLAY 0.723404 (-6075 4975);
PAINT MONO (-6075 4975);
DISPLAY INVISIBLE (-6075 4975);
FORCEPROP 1 LAST BODY_TYPE PLUMBING
J 0
(-6075 5025);
DISPLAY 0.872340 (-6075 5025);
PAINT GREEN (-6075 5025);
DISPLAY INVISIBLE (-6075 5025);
FORCEPROP 1 LAST HDL_TAP TRUE
J 0
(-5750 4850);
DISPLAY 0.872340 (-5750 4850);
DISPLAY INVISIBLE (-5750 4850);
FORCEPROP 1 LAST PATH I232
J 0
(-6077 4975);
DISPLAY 0.872340 (-6077 4975);
PAINT GREEN (-6077 4975);
DISPLAY INVISIBLE (-6077 4975);
FORCEADD TAP..1
(-6075 5075);
FORCEPROP 3 LASTPIN (-6125 5075) SIG_NAME M_F_CPU0_SA_DQ<18>
J 0
(-6115 5085);
DISPLAY 0.659574 (-6115 5085);
PAINT MONO (-6115 5085);
DISPLAY INVISIBLE (-6115 5085);
FORCEPROP 1 LASTPIN (-6125 5075) BN 18
J 0
(-6137 5083);
DISPLAY 0.489362 (-6137 5083);
PAINT GREEN (-6137 5083);
FORCEPROP 2 LAST CDS_LIB mstr_standard
J 0
(-6075 5075);
DISPLAY 0.723404 (-6075 5075);
PAINT MONO (-6075 5075);
DISPLAY INVISIBLE (-6075 5075);
FORCEPROP 1 LAST BODY_TYPE PLUMBING
J 0
(-6075 5125);
DISPLAY 0.872340 (-6075 5125);
PAINT GREEN (-6075 5125);
DISPLAY INVISIBLE (-6075 5125);
FORCEPROP 1 LAST HDL_TAP TRUE
J 0
(-5750 4950);
DISPLAY 0.872340 (-5750 4950);
DISPLAY INVISIBLE (-5750 4950);
FORCEPROP 1 LAST PATH I233
J 0
(-6077 5075);
DISPLAY 0.872340 (-6077 5075);
PAINT GREEN (-6077 5075);
DISPLAY INVISIBLE (-6077 5075);
FORCEADD TAP..1
(-6075 5025);
FORCEPROP 3 LASTPIN (-6125 5025) SIG_NAME M_F_CPU0_SA_DQ<17>
J 0
(-6115 5035);
DISPLAY 0.659574 (-6115 5035);
PAINT MONO (-6115 5035);
DISPLAY INVISIBLE (-6115 5035);
FORCEPROP 1 LASTPIN (-6125 5025) BN 17
J 0
(-6137 5033);
DISPLAY 0.489362 (-6137 5033);
PAINT GREEN (-6137 5033);
FORCEPROP 2 LAST CDS_LIB mstr_standard
J 0
(-6075 5025);
DISPLAY 0.723404 (-6075 5025);
PAINT MONO (-6075 5025);
DISPLAY INVISIBLE (-6075 5025);
FORCEPROP 1 LAST BODY_TYPE PLUMBING
J 0
(-6075 5075);
DISPLAY 0.872340 (-6075 5075);
PAINT GREEN (-6075 5075);
DISPLAY INVISIBLE (-6075 5075);
FORCEPROP 1 LAST HDL_TAP TRUE
J 0
(-5750 4900);
DISPLAY 0.872340 (-5750 4900);
DISPLAY INVISIBLE (-5750 4900);
FORCEPROP 1 LAST PATH I234
J 0
(-6077 5025);
DISPLAY 0.872340 (-6077 5025);
PAINT GREEN (-6077 5025);
DISPLAY INVISIBLE (-6077 5025);
FORCEADD TAP..1
(-6075 4725);
FORCEPROP 3 LASTPIN (-6125 4725) SIG_NAME M_F_CPU0_SA_DQ<11>
J 0
(-6115 4735);
DISPLAY 0.659574 (-6115 4735);
PAINT MONO (-6115 4735);
DISPLAY INVISIBLE (-6115 4735);
FORCEPROP 1 LASTPIN (-6125 4725) BN 11
J 0
(-6137 4733);
DISPLAY 0.489362 (-6137 4733);
PAINT GREEN (-6137 4733);
FORCEPROP 2 LAST CDS_LIB mstr_standard
J 0
(-6075 4725);
DISPLAY 0.723404 (-6075 4725);
PAINT MONO (-6075 4725);
DISPLAY INVISIBLE (-6075 4725);
FORCEPROP 1 LAST BODY_TYPE PLUMBING
J 0
(-6075 4775);
DISPLAY 0.872340 (-6075 4775);
PAINT GREEN (-6075 4775);
DISPLAY INVISIBLE (-6075 4775);
FORCEPROP 1 LAST HDL_TAP TRUE
J 0
(-5750 4600);
DISPLAY 0.872340 (-5750 4600);
DISPLAY INVISIBLE (-5750 4600);
FORCEPROP 1 LAST PATH I235
J 0
(-6077 4725);
DISPLAY 0.872340 (-6077 4725);
PAINT GREEN (-6077 4725);
DISPLAY INVISIBLE (-6077 4725);
FORCEADD TAP..1
(-6075 4775);
FORCEPROP 3 LASTPIN (-6125 4775) SIG_NAME M_F_CPU0_SA_DQ<12>
J 0
(-6115 4785);
DISPLAY 0.659574 (-6115 4785);
PAINT MONO (-6115 4785);
DISPLAY INVISIBLE (-6115 4785);
FORCEPROP 1 LASTPIN (-6125 4775) BN 12
J 0
(-6137 4783);
DISPLAY 0.489362 (-6137 4783);
PAINT GREEN (-6137 4783);
FORCEPROP 2 LAST CDS_LIB mstr_standard
J 0
(-6075 4775);
DISPLAY 0.723404 (-6075 4775);
PAINT MONO (-6075 4775);
DISPLAY INVISIBLE (-6075 4775);
FORCEPROP 1 LAST BODY_TYPE PLUMBING
J 0
(-6075 4825);
DISPLAY 0.872340 (-6075 4825);
PAINT GREEN (-6075 4825);
DISPLAY INVISIBLE (-6075 4825);
FORCEPROP 1 LAST HDL_TAP TRUE
J 0
(-5750 4650);
DISPLAY 0.872340 (-5750 4650);
DISPLAY INVISIBLE (-5750 4650);
FORCEPROP 1 LAST PATH I236
J 0
(-6077 4775);
DISPLAY 0.872340 (-6077 4775);
PAINT GREEN (-6077 4775);
DISPLAY INVISIBLE (-6077 4775);
FORCEADD TAP..1
(-6075 4825);
FORCEPROP 3 LASTPIN (-6125 4825) SIG_NAME M_F_CPU0_SA_DQ<13>
J 0
(-6115 4835);
DISPLAY 0.659574 (-6115 4835);
PAINT MONO (-6115 4835);
DISPLAY INVISIBLE (-6115 4835);
FORCEPROP 1 LASTPIN (-6125 4825) BN 13
J 0
(-6137 4833);
DISPLAY 0.489362 (-6137 4833);
PAINT GREEN (-6137 4833);
FORCEPROP 2 LAST CDS_LIB mstr_standard
J 0
(-6075 4825);
DISPLAY 0.723404 (-6075 4825);
PAINT MONO (-6075 4825);
DISPLAY INVISIBLE (-6075 4825);
FORCEPROP 1 LAST BODY_TYPE PLUMBING
J 0
(-6075 4875);
DISPLAY 0.872340 (-6075 4875);
PAINT GREEN (-6075 4875);
DISPLAY INVISIBLE (-6075 4875);
FORCEPROP 1 LAST HDL_TAP TRUE
J 0
(-5750 4700);
DISPLAY 0.872340 (-5750 4700);
DISPLAY INVISIBLE (-5750 4700);
FORCEPROP 1 LAST PATH I237
J 0
(-6077 4825);
DISPLAY 0.872340 (-6077 4825);
PAINT GREEN (-6077 4825);
DISPLAY INVISIBLE (-6077 4825);
FORCEADD TAP..1
(-6075 4925);
FORCEPROP 3 LASTPIN (-6125 4925) SIG_NAME M_F_CPU0_SA_DQ<15>
J 0
(-6115 4935);
DISPLAY 0.659574 (-6115 4935);
PAINT MONO (-6115 4935);
DISPLAY INVISIBLE (-6115 4935);
FORCEPROP 1 LASTPIN (-6125 4925) BN 15
J 0
(-6137 4933);
DISPLAY 0.489362 (-6137 4933);
PAINT GREEN (-6137 4933);
FORCEPROP 2 LAST CDS_LIB mstr_standard
J 0
(-6075 4925);
DISPLAY 0.723404 (-6075 4925);
PAINT MONO (-6075 4925);
DISPLAY INVISIBLE (-6075 4925);
FORCEPROP 1 LAST BODY_TYPE PLUMBING
J 0
(-6075 4975);
DISPLAY 0.872340 (-6075 4975);
PAINT GREEN (-6075 4975);
DISPLAY INVISIBLE (-6075 4975);
FORCEPROP 1 LAST HDL_TAP TRUE
J 0
(-5750 4800);
DISPLAY 0.872340 (-5750 4800);
DISPLAY INVISIBLE (-5750 4800);
FORCEPROP 1 LAST PATH I238
J 0
(-6077 4925);
DISPLAY 0.872340 (-6077 4925);
PAINT GREEN (-6077 4925);
DISPLAY INVISIBLE (-6077 4925);
FORCEADD TAP..1
(-6075 4875);
FORCEPROP 3 LASTPIN (-6125 4875) SIG_NAME M_F_CPU0_SA_DQ<14>
J 0
(-6115 4885);
DISPLAY 0.659574 (-6115 4885);
PAINT MONO (-6115 4885);
DISPLAY INVISIBLE (-6115 4885);
FORCEPROP 1 LASTPIN (-6125 4875) BN 14
J 0
(-6137 4883);
DISPLAY 0.489362 (-6137 4883);
PAINT GREEN (-6137 4883);
FORCEPROP 2 LAST CDS_LIB mstr_standard
J 0
(-6075 4875);
DISPLAY 0.723404 (-6075 4875);
PAINT MONO (-6075 4875);
DISPLAY INVISIBLE (-6075 4875);
FORCEPROP 1 LAST BODY_TYPE PLUMBING
J 0
(-6075 4925);
DISPLAY 0.872340 (-6075 4925);
PAINT GREEN (-6075 4925);
DISPLAY INVISIBLE (-6075 4925);
FORCEPROP 1 LAST HDL_TAP TRUE
J 0
(-5750 4750);
DISPLAY 0.872340 (-5750 4750);
DISPLAY INVISIBLE (-5750 4750);
FORCEPROP 1 LAST PATH I239
J 0
(-6077 4875);
DISPLAY 0.872340 (-6077 4875);
PAINT GREEN (-6077 4875);
DISPLAY INVISIBLE (-6077 4875);
FORCEADD TAP..1
(-6075 4675);
FORCEPROP 3 LASTPIN (-6125 4675) SIG_NAME M_F_CPU0_SA_DQ<10>
J 0
(-6115 4685);
DISPLAY 0.659574 (-6115 4685);
PAINT MONO (-6115 4685);
DISPLAY INVISIBLE (-6115 4685);
FORCEPROP 1 LASTPIN (-6125 4675) BN 10
J 0
(-6137 4683);
DISPLAY 0.489362 (-6137 4683);
PAINT GREEN (-6137 4683);
FORCEPROP 2 LAST CDS_LIB mstr_standard
J 0
(-6075 4675);
DISPLAY 0.723404 (-6075 4675);
PAINT MONO (-6075 4675);
DISPLAY INVISIBLE (-6075 4675);
FORCEPROP 1 LAST BODY_TYPE PLUMBING
J 0
(-6075 4725);
DISPLAY 0.872340 (-6075 4725);
PAINT GREEN (-6075 4725);
DISPLAY INVISIBLE (-6075 4725);
FORCEPROP 1 LAST HDL_TAP TRUE
J 0
(-5750 4550);
DISPLAY 0.872340 (-5750 4550);
DISPLAY INVISIBLE (-5750 4550);
FORCEPROP 1 LAST PATH I240
J 0
(-6077 4675);
DISPLAY 0.872340 (-6077 4675);
PAINT GREEN (-6077 4675);
DISPLAY INVISIBLE (-6077 4675);
FORCEADD TAP..1
(-6075 4625);
FORCEPROP 3 LASTPIN (-6125 4625) SIG_NAME M_F_CPU0_SA_DQ<9>
J 0
(-6115 4635);
DISPLAY 0.659574 (-6115 4635);
PAINT MONO (-6115 4635);
DISPLAY INVISIBLE (-6115 4635);
FORCEPROP 1 LASTPIN (-6125 4625) BN 9
J 0
(-6137 4633);
DISPLAY 0.489362 (-6137 4633);
PAINT GREEN (-6137 4633);
FORCEPROP 2 LAST CDS_LIB mstr_standard
J 0
(-6075 4625);
DISPLAY 0.723404 (-6075 4625);
PAINT MONO (-6075 4625);
DISPLAY INVISIBLE (-6075 4625);
FORCEPROP 1 LAST BODY_TYPE PLUMBING
J 0
(-6075 4675);
DISPLAY 0.872340 (-6075 4675);
PAINT GREEN (-6075 4675);
DISPLAY INVISIBLE (-6075 4675);
FORCEPROP 1 LAST HDL_TAP TRUE
J 0
(-5750 4500);
DISPLAY 0.872340 (-5750 4500);
DISPLAY INVISIBLE (-5750 4500);
FORCEPROP 1 LAST PATH I241
J 0
(-6077 4625);
DISPLAY 0.872340 (-6077 4625);
PAINT GREEN (-6077 4625);
DISPLAY INVISIBLE (-6077 4625);
FORCEADD TAP..1
(-6075 4575);
FORCEPROP 3 LASTPIN (-6125 4575) SIG_NAME M_F_CPU0_SA_DQ<8>
J 0
(-6115 4585);
DISPLAY 0.659574 (-6115 4585);
PAINT MONO (-6115 4585);
DISPLAY INVISIBLE (-6115 4585);
FORCEPROP 1 LASTPIN (-6125 4575) BN 8
J 0
(-6137 4583);
DISPLAY 0.489362 (-6137 4583);
PAINT GREEN (-6137 4583);
FORCEPROP 2 LAST CDS_LIB mstr_standard
J 0
(-6075 4575);
DISPLAY 0.723404 (-6075 4575);
PAINT MONO (-6075 4575);
DISPLAY INVISIBLE (-6075 4575);
FORCEPROP 1 LAST BODY_TYPE PLUMBING
J 0
(-6075 4625);
DISPLAY 0.872340 (-6075 4625);
PAINT GREEN (-6075 4625);
DISPLAY INVISIBLE (-6075 4625);
FORCEPROP 1 LAST HDL_TAP TRUE
J 0
(-5750 4450);
DISPLAY 0.872340 (-5750 4450);
DISPLAY INVISIBLE (-5750 4450);
FORCEPROP 1 LAST PATH I242
J 0
(-6077 4575);
DISPLAY 0.872340 (-6077 4575);
PAINT GREEN (-6077 4575);
DISPLAY INVISIBLE (-6077 4575);
FORCEADD TAP..1
(-6075 4475);
FORCEPROP 3 LASTPIN (-6125 4475) SIG_NAME M_F_CPU0_SA_DQ<6>
J 0
(-6115 4485);
DISPLAY 0.659574 (-6115 4485);
PAINT MONO (-6115 4485);
DISPLAY INVISIBLE (-6115 4485);
FORCEPROP 1 LASTPIN (-6125 4475) BN 6
J 0
(-6137 4483);
DISPLAY 0.489362 (-6137 4483);
PAINT GREEN (-6137 4483);
FORCEPROP 2 LAST CDS_LIB mstr_standard
J 0
(-6075 4475);
DISPLAY 0.723404 (-6075 4475);
PAINT MONO (-6075 4475);
DISPLAY INVISIBLE (-6075 4475);
FORCEPROP 1 LAST BODY_TYPE PLUMBING
J 0
(-6075 4525);
DISPLAY 0.872340 (-6075 4525);
PAINT GREEN (-6075 4525);
DISPLAY INVISIBLE (-6075 4525);
FORCEPROP 1 LAST HDL_TAP TRUE
J 0
(-5750 4350);
DISPLAY 0.872340 (-5750 4350);
DISPLAY INVISIBLE (-5750 4350);
FORCEPROP 1 LAST PATH I243
J 0
(-6077 4475);
DISPLAY 0.872340 (-6077 4475);
PAINT GREEN (-6077 4475);
DISPLAY INVISIBLE (-6077 4475);
FORCEADD TAP..1
(-6075 4525);
FORCEPROP 3 LASTPIN (-6125 4525) SIG_NAME M_F_CPU0_SA_DQ<7>
J 0
(-6115 4535);
DISPLAY 0.659574 (-6115 4535);
PAINT MONO (-6115 4535);
DISPLAY INVISIBLE (-6115 4535);
FORCEPROP 1 LASTPIN (-6125 4525) BN 7
J 0
(-6137 4533);
DISPLAY 0.489362 (-6137 4533);
PAINT GREEN (-6137 4533);
FORCEPROP 2 LAST CDS_LIB mstr_standard
J 0
(-6075 4525);
DISPLAY 0.723404 (-6075 4525);
PAINT MONO (-6075 4525);
DISPLAY INVISIBLE (-6075 4525);
FORCEPROP 1 LAST BODY_TYPE PLUMBING
J 0
(-6075 4575);
DISPLAY 0.872340 (-6075 4575);
PAINT GREEN (-6075 4575);
DISPLAY INVISIBLE (-6075 4575);
FORCEPROP 1 LAST HDL_TAP TRUE
J 0
(-5750 4400);
DISPLAY 0.872340 (-5750 4400);
DISPLAY INVISIBLE (-5750 4400);
FORCEPROP 1 LAST PATH I244
J 0
(-6077 4525);
DISPLAY 0.872340 (-6077 4525);
PAINT GREEN (-6077 4525);
DISPLAY INVISIBLE (-6077 4525);
FORCEADD TAP..1
(-6075 4425);
FORCEPROP 3 LASTPIN (-6125 4425) SIG_NAME M_F_CPU0_SA_DQ<5>
J 0
(-6115 4435);
DISPLAY 0.659574 (-6115 4435);
PAINT MONO (-6115 4435);
DISPLAY INVISIBLE (-6115 4435);
FORCEPROP 1 LASTPIN (-6125 4425) BN 5
J 0
(-6137 4433);
DISPLAY 0.489362 (-6137 4433);
PAINT GREEN (-6137 4433);
FORCEPROP 2 LAST CDS_LIB mstr_standard
J 0
(-6075 4425);
DISPLAY 0.723404 (-6075 4425);
PAINT MONO (-6075 4425);
DISPLAY INVISIBLE (-6075 4425);
FORCEPROP 1 LAST BODY_TYPE PLUMBING
J 0
(-6075 4475);
DISPLAY 0.872340 (-6075 4475);
PAINT GREEN (-6075 4475);
DISPLAY INVISIBLE (-6075 4475);
FORCEPROP 1 LAST HDL_TAP TRUE
J 0
(-5750 4300);
DISPLAY 0.872340 (-5750 4300);
DISPLAY INVISIBLE (-5750 4300);
FORCEPROP 1 LAST PATH I245
J 0
(-6077 4425);
DISPLAY 0.872340 (-6077 4425);
PAINT GREEN (-6077 4425);
DISPLAY INVISIBLE (-6077 4425);
FORCEADD TAP..1
(-6075 4375);
FORCEPROP 3 LASTPIN (-6125 4375) SIG_NAME M_F_CPU0_SA_DQ<4>
J 0
(-6115 4385);
DISPLAY 0.659574 (-6115 4385);
PAINT MONO (-6115 4385);
DISPLAY INVISIBLE (-6115 4385);
FORCEPROP 1 LASTPIN (-6125 4375) BN 4
J 0
(-6137 4383);
DISPLAY 0.489362 (-6137 4383);
PAINT GREEN (-6137 4383);
FORCEPROP 2 LAST CDS_LIB mstr_standard
J 0
(-6075 4375);
DISPLAY 0.723404 (-6075 4375);
PAINT MONO (-6075 4375);
DISPLAY INVISIBLE (-6075 4375);
FORCEPROP 1 LAST BODY_TYPE PLUMBING
J 0
(-6075 4425);
DISPLAY 0.872340 (-6075 4425);
PAINT GREEN (-6075 4425);
DISPLAY INVISIBLE (-6075 4425);
FORCEPROP 1 LAST HDL_TAP TRUE
J 0
(-5750 4250);
DISPLAY 0.872340 (-5750 4250);
DISPLAY INVISIBLE (-5750 4250);
FORCEPROP 1 LAST PATH I246
J 0
(-6077 4375);
DISPLAY 0.872340 (-6077 4375);
PAINT GREEN (-6077 4375);
DISPLAY INVISIBLE (-6077 4375);
FORCEADD TAP..1
(-6075 4325);
FORCEPROP 3 LASTPIN (-6125 4325) SIG_NAME M_F_CPU0_SA_DQ<3>
J 0
(-6115 4335);
DISPLAY 0.659574 (-6115 4335);
PAINT MONO (-6115 4335);
DISPLAY INVISIBLE (-6115 4335);
FORCEPROP 1 LASTPIN (-6125 4325) BN 3
J 0
(-6137 4333);
DISPLAY 0.489362 (-6137 4333);
PAINT GREEN (-6137 4333);
FORCEPROP 2 LAST CDS_LIB mstr_standard
J 0
(-6075 4325);
DISPLAY 0.723404 (-6075 4325);
PAINT MONO (-6075 4325);
DISPLAY INVISIBLE (-6075 4325);
FORCEPROP 1 LAST BODY_TYPE PLUMBING
J 0
(-6075 4375);
DISPLAY 0.872340 (-6075 4375);
PAINT GREEN (-6075 4375);
DISPLAY INVISIBLE (-6075 4375);
FORCEPROP 1 LAST HDL_TAP TRUE
J 0
(-5750 4200);
DISPLAY 0.872340 (-5750 4200);
DISPLAY INVISIBLE (-5750 4200);
FORCEPROP 1 LAST PATH I247
J 0
(-6077 4325);
DISPLAY 0.872340 (-6077 4325);
PAINT GREEN (-6077 4325);
DISPLAY INVISIBLE (-6077 4325);
FORCEADD TAP..1
(-6075 4225);
FORCEPROP 3 LASTPIN (-6125 4225) SIG_NAME M_F_CPU0_SA_DQ<1>
J 0
(-6115 4235);
DISPLAY 0.659574 (-6115 4235);
PAINT MONO (-6115 4235);
DISPLAY INVISIBLE (-6115 4235);
FORCEPROP 1 LASTPIN (-6125 4225) BN 1
J 0
(-6137 4233);
DISPLAY 0.489362 (-6137 4233);
PAINT GREEN (-6137 4233);
FORCEPROP 2 LAST CDS_LIB mstr_standard
J 0
(-6075 4225);
DISPLAY 0.723404 (-6075 4225);
PAINT MONO (-6075 4225);
DISPLAY INVISIBLE (-6075 4225);
FORCEPROP 1 LAST BODY_TYPE PLUMBING
J 0
(-6075 4275);
DISPLAY 0.872340 (-6075 4275);
PAINT GREEN (-6075 4275);
DISPLAY INVISIBLE (-6075 4275);
FORCEPROP 1 LAST HDL_TAP TRUE
J 0
(-5750 4100);
DISPLAY 0.872340 (-5750 4100);
DISPLAY INVISIBLE (-5750 4100);
FORCEPROP 1 LAST PATH I248
J 0
(-6077 4225);
DISPLAY 0.872340 (-6077 4225);
PAINT GREEN (-6077 4225);
DISPLAY INVISIBLE (-6077 4225);
FORCEADD TAP..1
(-6075 4275);
FORCEPROP 3 LASTPIN (-6125 4275) SIG_NAME M_F_CPU0_SA_DQ<2>
J 0
(-6115 4285);
DISPLAY 0.659574 (-6115 4285);
PAINT MONO (-6115 4285);
DISPLAY INVISIBLE (-6115 4285);
FORCEPROP 1 LASTPIN (-6125 4275) BN 2
J 0
(-6137 4283);
DISPLAY 0.489362 (-6137 4283);
PAINT GREEN (-6137 4283);
FORCEPROP 2 LAST CDS_LIB mstr_standard
J 0
(-6075 4275);
DISPLAY 0.723404 (-6075 4275);
PAINT MONO (-6075 4275);
DISPLAY INVISIBLE (-6075 4275);
FORCEPROP 1 LAST BODY_TYPE PLUMBING
J 0
(-6075 4325);
DISPLAY 0.872340 (-6075 4325);
PAINT GREEN (-6075 4325);
DISPLAY INVISIBLE (-6075 4325);
FORCEPROP 1 LAST HDL_TAP TRUE
J 0
(-5750 4150);
DISPLAY 0.872340 (-5750 4150);
DISPLAY INVISIBLE (-5750 4150);
FORCEPROP 1 LAST PATH I249
J 0
(-6077 4275);
DISPLAY 0.872340 (-6077 4275);
PAINT GREEN (-6077 4275);
DISPLAY INVISIBLE (-6077 4275);
FORCEADD TAP..1
(-6075 3975);
FORCEPROP 3 LASTPIN (-6125 3975) SIG_NAME M_F_CPU0_SB_DQ<29>
J 0
(-6115 3985);
DISPLAY 0.659574 (-6115 3985);
PAINT MONO (-6115 3985);
DISPLAY INVISIBLE (-6115 3985);
FORCEPROP 1 LASTPIN (-6125 3975) BN 29
J 0
(-6137 3983);
DISPLAY 0.489362 (-6137 3983);
PAINT GREEN (-6137 3983);
FORCEPROP 2 LAST CDS_LIB mstr_standard
J 0
(-6075 3975);
DISPLAY 0.723404 (-6075 3975);
PAINT MONO (-6075 3975);
DISPLAY INVISIBLE (-6075 3975);
FORCEPROP 1 LAST BODY_TYPE PLUMBING
J 0
(-6075 4025);
DISPLAY 0.872340 (-6075 4025);
PAINT GREEN (-6075 4025);
DISPLAY INVISIBLE (-6075 4025);
FORCEPROP 1 LAST HDL_TAP TRUE
J 0
(-5750 3850);
DISPLAY 0.872340 (-5750 3850);
DISPLAY INVISIBLE (-5750 3850);
FORCEPROP 1 LAST PATH I250
J 0
(-6077 3975);
DISPLAY 0.872340 (-6077 3975);
PAINT GREEN (-6077 3975);
DISPLAY INVISIBLE (-6077 3975);
FORCEADD TAP..1
(-6075 4075);
FORCEPROP 3 LASTPIN (-6125 4075) SIG_NAME M_F_CPU0_SB_DQ<31>
J 0
(-6115 4085);
DISPLAY 0.659574 (-6115 4085);
PAINT MONO (-6115 4085);
DISPLAY INVISIBLE (-6115 4085);
FORCEPROP 1 LASTPIN (-6125 4075) BN 31
J 0
(-6137 4083);
DISPLAY 0.489362 (-6137 4083);
PAINT GREEN (-6137 4083);
FORCEPROP 2 LAST CDS_LIB mstr_standard
J 0
(-6075 4075);
DISPLAY 0.723404 (-6075 4075);
PAINT MONO (-6075 4075);
DISPLAY INVISIBLE (-6075 4075);
FORCEPROP 1 LAST BODY_TYPE PLUMBING
J 0
(-6075 4125);
DISPLAY 0.872340 (-6075 4125);
PAINT GREEN (-6075 4125);
DISPLAY INVISIBLE (-6075 4125);
FORCEPROP 1 LAST HDL_TAP TRUE
J 0
(-5750 3950);
DISPLAY 0.872340 (-5750 3950);
DISPLAY INVISIBLE (-5750 3950);
FORCEPROP 1 LAST PATH I251
J 0
(-6077 4075);
DISPLAY 0.872340 (-6077 4075);
PAINT GREEN (-6077 4075);
DISPLAY INVISIBLE (-6077 4075);
FORCEADD TAP..1
(-6075 4025);
FORCEPROP 3 LASTPIN (-6125 4025) SIG_NAME M_F_CPU0_SB_DQ<30>
J 0
(-6115 4035);
DISPLAY 0.659574 (-6115 4035);
PAINT MONO (-6115 4035);
DISPLAY INVISIBLE (-6115 4035);
FORCEPROP 1 LASTPIN (-6125 4025) BN 30
J 0
(-6137 4033);
DISPLAY 0.489362 (-6137 4033);
PAINT GREEN (-6137 4033);
FORCEPROP 2 LAST CDS_LIB mstr_standard
J 0
(-6075 4025);
DISPLAY 0.723404 (-6075 4025);
PAINT MONO (-6075 4025);
DISPLAY INVISIBLE (-6075 4025);
FORCEPROP 1 LAST BODY_TYPE PLUMBING
J 0
(-6075 4075);
DISPLAY 0.872340 (-6075 4075);
PAINT GREEN (-6075 4075);
DISPLAY INVISIBLE (-6075 4075);
FORCEPROP 1 LAST HDL_TAP TRUE
J 0
(-5750 3900);
DISPLAY 0.872340 (-5750 3900);
DISPLAY INVISIBLE (-5750 3900);
FORCEPROP 1 LAST PATH I252
J 0
(-6077 4025);
DISPLAY 0.872340 (-6077 4025);
PAINT GREEN (-6077 4025);
DISPLAY INVISIBLE (-6077 4025);
FORCEADD TAP..1
(-6075 4175);
FORCEPROP 3 LASTPIN (-6125 4175) SIG_NAME M_F_CPU0_SA_DQ<0>
J 0
(-6115 4185);
DISPLAY 0.659574 (-6115 4185);
PAINT MONO (-6115 4185);
DISPLAY INVISIBLE (-6115 4185);
FORCEPROP 1 LASTPIN (-6125 4175) BN 0
J 0
(-6137 4183);
DISPLAY 0.489362 (-6137 4183);
PAINT GREEN (-6137 4183);
FORCEPROP 2 LAST CDS_LIB mstr_standard
J 0
(-6075 4175);
DISPLAY 0.723404 (-6075 4175);
PAINT MONO (-6075 4175);
DISPLAY INVISIBLE (-6075 4175);
FORCEPROP 1 LAST BODY_TYPE PLUMBING
J 0
(-6075 4225);
DISPLAY 0.872340 (-6075 4225);
PAINT GREEN (-6075 4225);
DISPLAY INVISIBLE (-6075 4225);
FORCEPROP 1 LAST HDL_TAP TRUE
J 0
(-5750 4050);
DISPLAY 0.872340 (-5750 4050);
DISPLAY INVISIBLE (-5750 4050);
FORCEPROP 1 LAST PATH I253
J 0
(-6077 4175);
DISPLAY 0.872340 (-6077 4175);
PAINT GREEN (-6077 4175);
DISPLAY INVISIBLE (-6077 4175);
FORCEADD TAP..1
(-6075 3725);
FORCEPROP 3 LASTPIN (-6125 3725) SIG_NAME M_F_CPU0_SB_DQ<24>
J 0
(-6115 3735);
DISPLAY 0.659574 (-6115 3735);
PAINT MONO (-6115 3735);
DISPLAY INVISIBLE (-6115 3735);
FORCEPROP 1 LASTPIN (-6125 3725) BN 24
J 0
(-6137 3733);
DISPLAY 0.489362 (-6137 3733);
PAINT GREEN (-6137 3733);
FORCEPROP 2 LAST CDS_LIB mstr_standard
J 0
(-6075 3725);
DISPLAY 0.723404 (-6075 3725);
PAINT MONO (-6075 3725);
DISPLAY INVISIBLE (-6075 3725);
FORCEPROP 1 LAST BODY_TYPE PLUMBING
J 0
(-6075 3775);
DISPLAY 0.872340 (-6075 3775);
PAINT GREEN (-6075 3775);
DISPLAY INVISIBLE (-6075 3775);
FORCEPROP 1 LAST HDL_TAP TRUE
J 0
(-5750 3600);
DISPLAY 0.872340 (-5750 3600);
DISPLAY INVISIBLE (-5750 3600);
FORCEPROP 1 LAST PATH I254
J 0
(-6077 3725);
DISPLAY 0.872340 (-6077 3725);
PAINT GREEN (-6077 3725);
DISPLAY INVISIBLE (-6077 3725);
FORCEADD TAP..1
(-6075 3925);
FORCEPROP 3 LASTPIN (-6125 3925) SIG_NAME M_F_CPU0_SB_DQ<28>
J 0
(-6115 3935);
DISPLAY 0.659574 (-6115 3935);
PAINT MONO (-6115 3935);
DISPLAY INVISIBLE (-6115 3935);
FORCEPROP 1 LASTPIN (-6125 3925) BN 28
J 0
(-6137 3933);
DISPLAY 0.489362 (-6137 3933);
PAINT GREEN (-6137 3933);
FORCEPROP 2 LAST CDS_LIB mstr_standard
J 0
(-6075 3925);
DISPLAY 0.723404 (-6075 3925);
PAINT MONO (-6075 3925);
DISPLAY INVISIBLE (-6075 3925);
FORCEPROP 1 LAST BODY_TYPE PLUMBING
J 0
(-6075 3975);
DISPLAY 0.872340 (-6075 3975);
PAINT GREEN (-6075 3975);
DISPLAY INVISIBLE (-6075 3975);
FORCEPROP 1 LAST HDL_TAP TRUE
J 0
(-5750 3800);
DISPLAY 0.872340 (-5750 3800);
DISPLAY INVISIBLE (-5750 3800);
FORCEPROP 1 LAST PATH I255
J 0
(-6077 3925);
DISPLAY 0.872340 (-6077 3925);
PAINT GREEN (-6077 3925);
DISPLAY INVISIBLE (-6077 3925);
FORCEADD TAP..1
(-6075 3775);
FORCEPROP 3 LASTPIN (-6125 3775) SIG_NAME M_F_CPU0_SB_DQ<25>
J 0
(-6115 3785);
DISPLAY 0.659574 (-6115 3785);
PAINT MONO (-6115 3785);
DISPLAY INVISIBLE (-6115 3785);
FORCEPROP 1 LASTPIN (-6125 3775) BN 25
J 0
(-6137 3783);
DISPLAY 0.489362 (-6137 3783);
PAINT GREEN (-6137 3783);
FORCEPROP 2 LAST CDS_LIB mstr_standard
J 0
(-6075 3775);
DISPLAY 0.723404 (-6075 3775);
PAINT MONO (-6075 3775);
DISPLAY INVISIBLE (-6075 3775);
FORCEPROP 1 LAST BODY_TYPE PLUMBING
J 0
(-6075 3825);
DISPLAY 0.872340 (-6075 3825);
PAINT GREEN (-6075 3825);
DISPLAY INVISIBLE (-6075 3825);
FORCEPROP 1 LAST HDL_TAP TRUE
J 0
(-5750 3650);
DISPLAY 0.872340 (-5750 3650);
DISPLAY INVISIBLE (-5750 3650);
FORCEPROP 1 LAST PATH I256
J 0
(-6077 3775);
DISPLAY 0.872340 (-6077 3775);
PAINT GREEN (-6077 3775);
DISPLAY INVISIBLE (-6077 3775);
FORCEADD TAP..1
(-6075 3875);
FORCEPROP 3 LASTPIN (-6125 3875) SIG_NAME M_F_CPU0_SB_DQ<27>
J 0
(-6115 3885);
DISPLAY 0.659574 (-6115 3885);
PAINT MONO (-6115 3885);
DISPLAY INVISIBLE (-6115 3885);
FORCEPROP 1 LASTPIN (-6125 3875) BN 27
J 0
(-6137 3883);
DISPLAY 0.489362 (-6137 3883);
PAINT GREEN (-6137 3883);
FORCEPROP 2 LAST CDS_LIB mstr_standard
J 0
(-6075 3875);
DISPLAY 0.723404 (-6075 3875);
PAINT MONO (-6075 3875);
DISPLAY INVISIBLE (-6075 3875);
FORCEPROP 1 LAST BODY_TYPE PLUMBING
J 0
(-6075 3925);
DISPLAY 0.872340 (-6075 3925);
PAINT GREEN (-6075 3925);
DISPLAY INVISIBLE (-6075 3925);
FORCEPROP 1 LAST HDL_TAP TRUE
J 0
(-5750 3750);
DISPLAY 0.872340 (-5750 3750);
DISPLAY INVISIBLE (-5750 3750);
FORCEPROP 1 LAST PATH I257
J 0
(-6077 3875);
DISPLAY 0.872340 (-6077 3875);
PAINT GREEN (-6077 3875);
DISPLAY INVISIBLE (-6077 3875);
FORCEADD TAP..1
(-6075 3825);
FORCEPROP 3 LASTPIN (-6125 3825) SIG_NAME M_F_CPU0_SB_DQ<26>
J 0
(-6115 3835);
DISPLAY 0.659574 (-6115 3835);
PAINT MONO (-6115 3835);
DISPLAY INVISIBLE (-6115 3835);
FORCEPROP 1 LASTPIN (-6125 3825) BN 26
J 0
(-6137 3833);
DISPLAY 0.489362 (-6137 3833);
PAINT GREEN (-6137 3833);
FORCEPROP 2 LAST CDS_LIB mstr_standard
J 0
(-6075 3825);
DISPLAY 0.723404 (-6075 3825);
PAINT MONO (-6075 3825);
DISPLAY INVISIBLE (-6075 3825);
FORCEPROP 1 LAST BODY_TYPE PLUMBING
J 0
(-6075 3875);
DISPLAY 0.872340 (-6075 3875);
PAINT GREEN (-6075 3875);
DISPLAY INVISIBLE (-6075 3875);
FORCEPROP 1 LAST HDL_TAP TRUE
J 0
(-5750 3700);
DISPLAY 0.872340 (-5750 3700);
DISPLAY INVISIBLE (-5750 3700);
FORCEPROP 1 LAST PATH I258
J 0
(-6077 3825);
DISPLAY 0.872340 (-6077 3825);
PAINT GREEN (-6077 3825);
DISPLAY INVISIBLE (-6077 3825);
FORCEADD TAP..1
(-6075 3475);
FORCEPROP 3 LASTPIN (-6125 3475) SIG_NAME M_F_CPU0_SB_DQ<19>
J 0
(-6115 3485);
DISPLAY 0.659574 (-6115 3485);
PAINT MONO (-6115 3485);
DISPLAY INVISIBLE (-6115 3485);
FORCEPROP 1 LASTPIN (-6125 3475) BN 19
J 0
(-6137 3483);
DISPLAY 0.489362 (-6137 3483);
PAINT GREEN (-6137 3483);
FORCEPROP 2 LAST CDS_LIB mstr_standard
J 0
(-6075 3475);
DISPLAY 0.723404 (-6075 3475);
PAINT MONO (-6075 3475);
DISPLAY INVISIBLE (-6075 3475);
FORCEPROP 1 LAST BODY_TYPE PLUMBING
J 0
(-6075 3525);
DISPLAY 0.872340 (-6075 3525);
PAINT GREEN (-6075 3525);
DISPLAY INVISIBLE (-6075 3525);
FORCEPROP 1 LAST HDL_TAP TRUE
J 0
(-5750 3350);
DISPLAY 0.872340 (-5750 3350);
DISPLAY INVISIBLE (-5750 3350);
FORCEPROP 1 LAST PATH I259
J 0
(-6077 3475);
DISPLAY 0.872340 (-6077 3475);
PAINT GREEN (-6077 3475);
DISPLAY INVISIBLE (-6077 3475);
FORCEADD TAP..1
(-6075 3675);
FORCEPROP 3 LASTPIN (-6125 3675) SIG_NAME M_F_CPU0_SB_DQ<23>
J 0
(-6115 3685);
DISPLAY 0.659574 (-6115 3685);
PAINT MONO (-6115 3685);
DISPLAY INVISIBLE (-6115 3685);
FORCEPROP 1 LASTPIN (-6125 3675) BN 23
J 0
(-6137 3683);
DISPLAY 0.489362 (-6137 3683);
PAINT GREEN (-6137 3683);
FORCEPROP 2 LAST CDS_LIB mstr_standard
J 0
(-6075 3675);
DISPLAY 0.723404 (-6075 3675);
PAINT MONO (-6075 3675);
DISPLAY INVISIBLE (-6075 3675);
FORCEPROP 1 LAST BODY_TYPE PLUMBING
J 0
(-6075 3725);
DISPLAY 0.872340 (-6075 3725);
PAINT GREEN (-6075 3725);
DISPLAY INVISIBLE (-6075 3725);
FORCEPROP 1 LAST HDL_TAP TRUE
J 0
(-5750 3550);
DISPLAY 0.872340 (-5750 3550);
DISPLAY INVISIBLE (-5750 3550);
FORCEPROP 1 LAST PATH I260
J 0
(-6077 3675);
DISPLAY 0.872340 (-6077 3675);
PAINT GREEN (-6077 3675);
DISPLAY INVISIBLE (-6077 3675);
FORCEADD TAP..1
(-6075 3525);
FORCEPROP 3 LASTPIN (-6125 3525) SIG_NAME M_F_CPU0_SB_DQ<20>
J 0
(-6115 3535);
DISPLAY 0.659574 (-6115 3535);
PAINT MONO (-6115 3535);
DISPLAY INVISIBLE (-6115 3535);
FORCEPROP 1 LASTPIN (-6125 3525) BN 20
J 0
(-6137 3533);
DISPLAY 0.489362 (-6137 3533);
PAINT GREEN (-6137 3533);
FORCEPROP 2 LAST CDS_LIB mstr_standard
J 0
(-6075 3525);
DISPLAY 0.723404 (-6075 3525);
PAINT MONO (-6075 3525);
DISPLAY INVISIBLE (-6075 3525);
FORCEPROP 1 LAST BODY_TYPE PLUMBING
J 0
(-6075 3575);
DISPLAY 0.872340 (-6075 3575);
PAINT GREEN (-6075 3575);
DISPLAY INVISIBLE (-6075 3575);
FORCEPROP 1 LAST HDL_TAP TRUE
J 0
(-5750 3400);
DISPLAY 0.872340 (-5750 3400);
DISPLAY INVISIBLE (-5750 3400);
FORCEPROP 1 LAST PATH I261
J 0
(-6077 3525);
DISPLAY 0.872340 (-6077 3525);
PAINT GREEN (-6077 3525);
DISPLAY INVISIBLE (-6077 3525);
FORCEADD TAP..1
(-6075 3625);
FORCEPROP 3 LASTPIN (-6125 3625) SIG_NAME M_F_CPU0_SB_DQ<22>
J 0
(-6115 3635);
DISPLAY 0.659574 (-6115 3635);
PAINT MONO (-6115 3635);
DISPLAY INVISIBLE (-6115 3635);
FORCEPROP 1 LASTPIN (-6125 3625) BN 22
J 0
(-6137 3633);
DISPLAY 0.489362 (-6137 3633);
PAINT GREEN (-6137 3633);
FORCEPROP 2 LAST CDS_LIB mstr_standard
J 0
(-6075 3625);
DISPLAY 0.723404 (-6075 3625);
PAINT MONO (-6075 3625);
DISPLAY INVISIBLE (-6075 3625);
FORCEPROP 1 LAST BODY_TYPE PLUMBING
J 0
(-6075 3675);
DISPLAY 0.872340 (-6075 3675);
PAINT GREEN (-6075 3675);
DISPLAY INVISIBLE (-6075 3675);
FORCEPROP 1 LAST HDL_TAP TRUE
J 0
(-5750 3500);
DISPLAY 0.872340 (-5750 3500);
DISPLAY INVISIBLE (-5750 3500);
FORCEPROP 1 LAST PATH I262
J 0
(-6077 3625);
DISPLAY 0.872340 (-6077 3625);
PAINT GREEN (-6077 3625);
DISPLAY INVISIBLE (-6077 3625);
FORCEADD TAP..1
(-6075 3575);
FORCEPROP 3 LASTPIN (-6125 3575) SIG_NAME M_F_CPU0_SB_DQ<21>
J 0
(-6115 3585);
DISPLAY 0.659574 (-6115 3585);
PAINT MONO (-6115 3585);
DISPLAY INVISIBLE (-6115 3585);
FORCEPROP 1 LASTPIN (-6125 3575) BN 21
J 0
(-6137 3583);
DISPLAY 0.489362 (-6137 3583);
PAINT GREEN (-6137 3583);
FORCEPROP 2 LAST CDS_LIB mstr_standard
J 0
(-6075 3575);
DISPLAY 0.723404 (-6075 3575);
PAINT MONO (-6075 3575);
DISPLAY INVISIBLE (-6075 3575);
FORCEPROP 1 LAST BODY_TYPE PLUMBING
J 0
(-6075 3625);
DISPLAY 0.872340 (-6075 3625);
PAINT GREEN (-6075 3625);
DISPLAY INVISIBLE (-6075 3625);
FORCEPROP 1 LAST HDL_TAP TRUE
J 0
(-5750 3450);
DISPLAY 0.872340 (-5750 3450);
DISPLAY INVISIBLE (-5750 3450);
FORCEPROP 1 LAST PATH I263
J 0
(-6077 3575);
DISPLAY 0.872340 (-6077 3575);
PAINT GREEN (-6077 3575);
DISPLAY INVISIBLE (-6077 3575);
FORCEADD TAP..1
(-6075 3325);
FORCEPROP 3 LASTPIN (-6125 3325) SIG_NAME M_F_CPU0_SB_DQ<16>
J 0
(-6115 3335);
DISPLAY 0.659574 (-6115 3335);
PAINT MONO (-6115 3335);
DISPLAY INVISIBLE (-6115 3335);
FORCEPROP 1 LASTPIN (-6125 3325) BN 16
J 0
(-6137 3333);
DISPLAY 0.489362 (-6137 3333);
PAINT GREEN (-6137 3333);
FORCEPROP 2 LAST CDS_LIB mstr_standard
J 0
(-6075 3325);
DISPLAY 0.723404 (-6075 3325);
PAINT MONO (-6075 3325);
DISPLAY INVISIBLE (-6075 3325);
FORCEPROP 1 LAST BODY_TYPE PLUMBING
J 0
(-6075 3375);
DISPLAY 0.872340 (-6075 3375);
PAINT GREEN (-6075 3375);
DISPLAY INVISIBLE (-6075 3375);
FORCEPROP 1 LAST HDL_TAP TRUE
J 0
(-5750 3200);
DISPLAY 0.872340 (-5750 3200);
DISPLAY INVISIBLE (-5750 3200);
FORCEPROP 1 LAST PATH I264
J 0
(-6077 3325);
DISPLAY 0.872340 (-6077 3325);
PAINT GREEN (-6077 3325);
DISPLAY INVISIBLE (-6077 3325);
FORCEADD TAP..1
(-6075 3375);
FORCEPROP 3 LASTPIN (-6125 3375) SIG_NAME M_F_CPU0_SB_DQ<17>
J 0
(-6115 3385);
DISPLAY 0.659574 (-6115 3385);
PAINT MONO (-6115 3385);
DISPLAY INVISIBLE (-6115 3385);
FORCEPROP 1 LASTPIN (-6125 3375) BN 17
J 0
(-6137 3383);
DISPLAY 0.489362 (-6137 3383);
PAINT GREEN (-6137 3383);
FORCEPROP 2 LAST CDS_LIB mstr_standard
J 0
(-6075 3375);
DISPLAY 0.723404 (-6075 3375);
PAINT MONO (-6075 3375);
DISPLAY INVISIBLE (-6075 3375);
FORCEPROP 1 LAST BODY_TYPE PLUMBING
J 0
(-6075 3425);
DISPLAY 0.872340 (-6075 3425);
PAINT GREEN (-6075 3425);
DISPLAY INVISIBLE (-6075 3425);
FORCEPROP 1 LAST HDL_TAP TRUE
J 0
(-5750 3250);
DISPLAY 0.872340 (-5750 3250);
DISPLAY INVISIBLE (-5750 3250);
FORCEPROP 1 LAST PATH I265
J 0
(-6077 3375);
DISPLAY 0.872340 (-6077 3375);
PAINT GREEN (-6077 3375);
DISPLAY INVISIBLE (-6077 3375);
FORCEADD TAP..1
(-6075 3425);
FORCEPROP 3 LASTPIN (-6125 3425) SIG_NAME M_F_CPU0_SB_DQ<18>
J 0
(-6115 3435);
DISPLAY 0.659574 (-6115 3435);
PAINT MONO (-6115 3435);
DISPLAY INVISIBLE (-6115 3435);
FORCEPROP 1 LASTPIN (-6125 3425) BN 18
J 0
(-6137 3433);
DISPLAY 0.489362 (-6137 3433);
PAINT GREEN (-6137 3433);
FORCEPROP 2 LAST CDS_LIB mstr_standard
J 0
(-6075 3425);
DISPLAY 0.723404 (-6075 3425);
PAINT MONO (-6075 3425);
DISPLAY INVISIBLE (-6075 3425);
FORCEPROP 1 LAST BODY_TYPE PLUMBING
J 0
(-6075 3475);
DISPLAY 0.872340 (-6075 3475);
PAINT GREEN (-6075 3475);
DISPLAY INVISIBLE (-6075 3475);
FORCEPROP 1 LAST HDL_TAP TRUE
J 0
(-5750 3300);
DISPLAY 0.872340 (-5750 3300);
DISPLAY INVISIBLE (-5750 3300);
FORCEPROP 1 LAST PATH I266
J 0
(-6077 3425);
DISPLAY 0.872340 (-6077 3425);
PAINT GREEN (-6077 3425);
DISPLAY INVISIBLE (-6077 3425);
FORCEADD TAP..1
(-6075 3225);
FORCEPROP 3 LASTPIN (-6125 3225) SIG_NAME M_F_CPU0_SB_DQ<14>
J 0
(-6115 3235);
DISPLAY 0.659574 (-6115 3235);
PAINT MONO (-6115 3235);
DISPLAY INVISIBLE (-6115 3235);
FORCEPROP 1 LASTPIN (-6125 3225) BN 14
J 0
(-6137 3233);
DISPLAY 0.489362 (-6137 3233);
PAINT GREEN (-6137 3233);
FORCEPROP 2 LAST CDS_LIB mstr_standard
J 0
(-6075 3225);
DISPLAY 0.723404 (-6075 3225);
PAINT MONO (-6075 3225);
DISPLAY INVISIBLE (-6075 3225);
FORCEPROP 1 LAST BODY_TYPE PLUMBING
J 0
(-6075 3275);
DISPLAY 0.872340 (-6075 3275);
PAINT GREEN (-6075 3275);
DISPLAY INVISIBLE (-6075 3275);
FORCEPROP 1 LAST HDL_TAP TRUE
J 0
(-5750 3100);
DISPLAY 0.872340 (-5750 3100);
DISPLAY INVISIBLE (-5750 3100);
FORCEPROP 1 LAST PATH I267
J 0
(-6077 3225);
DISPLAY 0.872340 (-6077 3225);
PAINT GREEN (-6077 3225);
DISPLAY INVISIBLE (-6077 3225);
FORCEADD TAP..1
(-6075 3275);
FORCEPROP 3 LASTPIN (-6125 3275) SIG_NAME M_F_CPU0_SB_DQ<15>
J 0
(-6115 3285);
DISPLAY 0.659574 (-6115 3285);
PAINT MONO (-6115 3285);
DISPLAY INVISIBLE (-6115 3285);
FORCEPROP 1 LASTPIN (-6125 3275) BN 15
J 0
(-6137 3283);
DISPLAY 0.489362 (-6137 3283);
PAINT GREEN (-6137 3283);
FORCEPROP 2 LAST CDS_LIB mstr_standard
J 0
(-6075 3275);
DISPLAY 0.723404 (-6075 3275);
PAINT MONO (-6075 3275);
DISPLAY INVISIBLE (-6075 3275);
FORCEPROP 1 LAST BODY_TYPE PLUMBING
J 0
(-6075 3325);
DISPLAY 0.872340 (-6075 3325);
PAINT GREEN (-6075 3325);
DISPLAY INVISIBLE (-6075 3325);
FORCEPROP 1 LAST HDL_TAP TRUE
J 0
(-5750 3150);
DISPLAY 0.872340 (-5750 3150);
DISPLAY INVISIBLE (-5750 3150);
FORCEPROP 1 LAST PATH I268
J 0
(-6077 3275);
DISPLAY 0.872340 (-6077 3275);
PAINT GREEN (-6077 3275);
DISPLAY INVISIBLE (-6077 3275);
FORCEADD TAP..1
(-6075 3175);
FORCEPROP 3 LASTPIN (-6125 3175) SIG_NAME M_F_CPU0_SB_DQ<13>
J 0
(-6115 3185);
DISPLAY 0.659574 (-6115 3185);
PAINT MONO (-6115 3185);
DISPLAY INVISIBLE (-6115 3185);
FORCEPROP 1 LASTPIN (-6125 3175) BN 13
J 0
(-6137 3183);
DISPLAY 0.489362 (-6137 3183);
PAINT GREEN (-6137 3183);
FORCEPROP 2 LAST CDS_LIB mstr_standard
J 0
(-6075 3175);
DISPLAY 0.723404 (-6075 3175);
PAINT MONO (-6075 3175);
DISPLAY INVISIBLE (-6075 3175);
FORCEPROP 1 LAST BODY_TYPE PLUMBING
J 0
(-6075 3225);
DISPLAY 0.872340 (-6075 3225);
PAINT GREEN (-6075 3225);
DISPLAY INVISIBLE (-6075 3225);
FORCEPROP 1 LAST HDL_TAP TRUE
J 0
(-5750 3050);
DISPLAY 0.872340 (-5750 3050);
DISPLAY INVISIBLE (-5750 3050);
FORCEPROP 1 LAST PATH I269
J 0
(-6077 3175);
DISPLAY 0.872340 (-6077 3175);
PAINT GREEN (-6077 3175);
DISPLAY INVISIBLE (-6077 3175);
FORCEADD TAP..1
(-6075 3125);
FORCEPROP 3 LASTPIN (-6125 3125) SIG_NAME M_F_CPU0_SB_DQ<12>
J 0
(-6115 3135);
DISPLAY 0.659574 (-6115 3135);
PAINT MONO (-6115 3135);
DISPLAY INVISIBLE (-6115 3135);
FORCEPROP 1 LASTPIN (-6125 3125) BN 12
J 0
(-6137 3133);
DISPLAY 0.489362 (-6137 3133);
PAINT GREEN (-6137 3133);
FORCEPROP 2 LAST CDS_LIB mstr_standard
J 0
(-6075 3125);
DISPLAY 0.723404 (-6075 3125);
PAINT MONO (-6075 3125);
DISPLAY INVISIBLE (-6075 3125);
FORCEPROP 1 LAST BODY_TYPE PLUMBING
J 0
(-6075 3175);
DISPLAY 0.872340 (-6075 3175);
PAINT GREEN (-6075 3175);
DISPLAY INVISIBLE (-6075 3175);
FORCEPROP 1 LAST HDL_TAP TRUE
J 0
(-5750 3000);
DISPLAY 0.872340 (-5750 3000);
DISPLAY INVISIBLE (-5750 3000);
FORCEPROP 1 LAST PATH I270
J 0
(-6077 3125);
DISPLAY 0.872340 (-6077 3125);
PAINT GREEN (-6077 3125);
DISPLAY INVISIBLE (-6077 3125);
FORCEADD TAP..1
(-6075 3075);
FORCEPROP 3 LASTPIN (-6125 3075) SIG_NAME M_F_CPU0_SB_DQ<11>
J 0
(-6115 3085);
DISPLAY 0.659574 (-6115 3085);
PAINT MONO (-6115 3085);
DISPLAY INVISIBLE (-6115 3085);
FORCEPROP 1 LASTPIN (-6125 3075) BN 11
J 0
(-6137 3083);
DISPLAY 0.489362 (-6137 3083);
PAINT GREEN (-6137 3083);
FORCEPROP 2 LAST CDS_LIB mstr_standard
J 0
(-6075 3075);
DISPLAY 0.723404 (-6075 3075);
PAINT MONO (-6075 3075);
DISPLAY INVISIBLE (-6075 3075);
FORCEPROP 1 LAST BODY_TYPE PLUMBING
J 0
(-6075 3125);
DISPLAY 0.872340 (-6075 3125);
PAINT GREEN (-6075 3125);
DISPLAY INVISIBLE (-6075 3125);
FORCEPROP 1 LAST HDL_TAP TRUE
J 0
(-5750 2950);
DISPLAY 0.872340 (-5750 2950);
DISPLAY INVISIBLE (-5750 2950);
FORCEPROP 1 LAST PATH I271
J 0
(-6077 3075);
DISPLAY 0.872340 (-6077 3075);
PAINT GREEN (-6077 3075);
DISPLAY INVISIBLE (-6077 3075);
FORCEADD TAP..1
(-6075 3025);
FORCEPROP 3 LASTPIN (-6125 3025) SIG_NAME M_F_CPU0_SB_DQ<10>
J 0
(-6115 3035);
DISPLAY 0.659574 (-6115 3035);
PAINT MONO (-6115 3035);
DISPLAY INVISIBLE (-6115 3035);
FORCEPROP 1 LASTPIN (-6125 3025) BN 10
J 0
(-6137 3033);
DISPLAY 0.489362 (-6137 3033);
PAINT GREEN (-6137 3033);
FORCEPROP 2 LAST CDS_LIB mstr_standard
J 0
(-6075 3025);
DISPLAY 0.723404 (-6075 3025);
PAINT MONO (-6075 3025);
DISPLAY INVISIBLE (-6075 3025);
FORCEPROP 1 LAST BODY_TYPE PLUMBING
J 0
(-6075 3075);
DISPLAY 0.872340 (-6075 3075);
PAINT GREEN (-6075 3075);
DISPLAY INVISIBLE (-6075 3075);
FORCEPROP 1 LAST HDL_TAP TRUE
J 0
(-5750 2900);
DISPLAY 0.872340 (-5750 2900);
DISPLAY INVISIBLE (-5750 2900);
FORCEPROP 1 LAST PATH I272
J 0
(-6077 3025);
DISPLAY 0.872340 (-6077 3025);
PAINT GREEN (-6077 3025);
DISPLAY INVISIBLE (-6077 3025);
FORCEADD TAP..1
(-6075 2975);
FORCEPROP 3 LASTPIN (-6125 2975) SIG_NAME M_F_CPU0_SB_DQ<9>
J 0
(-6115 2985);
DISPLAY 0.659574 (-6115 2985);
PAINT MONO (-6115 2985);
DISPLAY INVISIBLE (-6115 2985);
FORCEPROP 1 LASTPIN (-6125 2975) BN 9
J 0
(-6137 2983);
DISPLAY 0.489362 (-6137 2983);
PAINT GREEN (-6137 2983);
FORCEPROP 2 LAST CDS_LIB mstr_standard
J 0
(-6075 2975);
DISPLAY 0.723404 (-6075 2975);
PAINT MONO (-6075 2975);
DISPLAY INVISIBLE (-6075 2975);
FORCEPROP 1 LAST BODY_TYPE PLUMBING
J 0
(-6075 3025);
DISPLAY 0.872340 (-6075 3025);
PAINT GREEN (-6075 3025);
DISPLAY INVISIBLE (-6075 3025);
FORCEPROP 1 LAST HDL_TAP TRUE
J 0
(-5750 2850);
DISPLAY 0.872340 (-5750 2850);
DISPLAY INVISIBLE (-5750 2850);
FORCEPROP 1 LAST PATH I273
J 0
(-6077 2975);
DISPLAY 0.872340 (-6077 2975);
PAINT GREEN (-6077 2975);
DISPLAY INVISIBLE (-6077 2975);
FORCEADD TAP..1
(-6075 2925);
FORCEPROP 3 LASTPIN (-6125 2925) SIG_NAME M_F_CPU0_SB_DQ<8>
J 0
(-6115 2935);
DISPLAY 0.659574 (-6115 2935);
PAINT MONO (-6115 2935);
DISPLAY INVISIBLE (-6115 2935);
FORCEPROP 1 LASTPIN (-6125 2925) BN 8
J 0
(-6137 2933);
DISPLAY 0.489362 (-6137 2933);
PAINT GREEN (-6137 2933);
FORCEPROP 2 LAST CDS_LIB mstr_standard
J 0
(-6075 2925);
DISPLAY 0.723404 (-6075 2925);
PAINT MONO (-6075 2925);
DISPLAY INVISIBLE (-6075 2925);
FORCEPROP 1 LAST BODY_TYPE PLUMBING
J 0
(-6075 2975);
DISPLAY 0.872340 (-6075 2975);
PAINT GREEN (-6075 2975);
DISPLAY INVISIBLE (-6075 2975);
FORCEPROP 1 LAST HDL_TAP TRUE
J 0
(-5750 2800);
DISPLAY 0.872340 (-5750 2800);
DISPLAY INVISIBLE (-5750 2800);
FORCEPROP 1 LAST PATH I274
J 0
(-6077 2925);
DISPLAY 0.872340 (-6077 2925);
PAINT GREEN (-6077 2925);
DISPLAY INVISIBLE (-6077 2925);
FORCEADD TAP..1
(-6075 2825);
FORCEPROP 3 LASTPIN (-6125 2825) SIG_NAME M_F_CPU0_SB_DQ<6>
J 0
(-6115 2835);
DISPLAY 0.659574 (-6115 2835);
PAINT MONO (-6115 2835);
DISPLAY INVISIBLE (-6115 2835);
FORCEPROP 1 LASTPIN (-6125 2825) BN 6
J 0
(-6137 2833);
DISPLAY 0.489362 (-6137 2833);
PAINT GREEN (-6137 2833);
FORCEPROP 2 LAST CDS_LIB mstr_standard
J 0
(-6075 2825);
DISPLAY 0.723404 (-6075 2825);
PAINT MONO (-6075 2825);
DISPLAY INVISIBLE (-6075 2825);
FORCEPROP 1 LAST BODY_TYPE PLUMBING
J 0
(-6075 2875);
DISPLAY 0.872340 (-6075 2875);
PAINT GREEN (-6075 2875);
DISPLAY INVISIBLE (-6075 2875);
FORCEPROP 1 LAST HDL_TAP TRUE
J 0
(-5750 2700);
DISPLAY 0.872340 (-5750 2700);
DISPLAY INVISIBLE (-5750 2700);
FORCEPROP 1 LAST PATH I275
J 0
(-6077 2825);
DISPLAY 0.872340 (-6077 2825);
PAINT GREEN (-6077 2825);
DISPLAY INVISIBLE (-6077 2825);
FORCEADD TAP..1
(-6075 2875);
FORCEPROP 3 LASTPIN (-6125 2875) SIG_NAME M_F_CPU0_SB_DQ<7>
J 0
(-6115 2885);
DISPLAY 0.659574 (-6115 2885);
PAINT MONO (-6115 2885);
DISPLAY INVISIBLE (-6115 2885);
FORCEPROP 1 LASTPIN (-6125 2875) BN 7
J 0
(-6137 2883);
DISPLAY 0.489362 (-6137 2883);
PAINT GREEN (-6137 2883);
FORCEPROP 2 LAST CDS_LIB mstr_standard
J 0
(-6075 2875);
DISPLAY 0.723404 (-6075 2875);
PAINT MONO (-6075 2875);
DISPLAY INVISIBLE (-6075 2875);
FORCEPROP 1 LAST BODY_TYPE PLUMBING
J 0
(-6075 2925);
DISPLAY 0.872340 (-6075 2925);
PAINT GREEN (-6075 2925);
DISPLAY INVISIBLE (-6075 2925);
FORCEPROP 1 LAST HDL_TAP TRUE
J 0
(-5750 2750);
DISPLAY 0.872340 (-5750 2750);
DISPLAY INVISIBLE (-5750 2750);
FORCEPROP 1 LAST PATH I276
J 0
(-6077 2875);
DISPLAY 0.872340 (-6077 2875);
PAINT GREEN (-6077 2875);
DISPLAY INVISIBLE (-6077 2875);
FORCEADD TAP..1
(-6075 2775);
FORCEPROP 3 LASTPIN (-6125 2775) SIG_NAME M_F_CPU0_SB_DQ<5>
J 0
(-6115 2785);
DISPLAY 0.659574 (-6115 2785);
PAINT MONO (-6115 2785);
DISPLAY INVISIBLE (-6115 2785);
FORCEPROP 1 LASTPIN (-6125 2775) BN 5
J 0
(-6137 2783);
DISPLAY 0.489362 (-6137 2783);
PAINT GREEN (-6137 2783);
FORCEPROP 2 LAST CDS_LIB mstr_standard
J 0
(-6075 2775);
DISPLAY 0.723404 (-6075 2775);
PAINT MONO (-6075 2775);
DISPLAY INVISIBLE (-6075 2775);
FORCEPROP 1 LAST BODY_TYPE PLUMBING
J 0
(-6075 2825);
DISPLAY 0.872340 (-6075 2825);
PAINT GREEN (-6075 2825);
DISPLAY INVISIBLE (-6075 2825);
FORCEPROP 1 LAST HDL_TAP TRUE
J 0
(-5750 2650);
DISPLAY 0.872340 (-5750 2650);
DISPLAY INVISIBLE (-5750 2650);
FORCEPROP 1 LAST PATH I277
J 0
(-6077 2775);
DISPLAY 0.872340 (-6077 2775);
PAINT GREEN (-6077 2775);
DISPLAY INVISIBLE (-6077 2775);
FORCEADD TAP..1
(-6075 2725);
FORCEPROP 3 LASTPIN (-6125 2725) SIG_NAME M_F_CPU0_SB_DQ<4>
J 0
(-6115 2735);
DISPLAY 0.659574 (-6115 2735);
PAINT MONO (-6115 2735);
DISPLAY INVISIBLE (-6115 2735);
FORCEPROP 1 LASTPIN (-6125 2725) BN 4
J 0
(-6137 2733);
DISPLAY 0.489362 (-6137 2733);
PAINT GREEN (-6137 2733);
FORCEPROP 2 LAST CDS_LIB mstr_standard
J 0
(-6075 2725);
DISPLAY 0.723404 (-6075 2725);
PAINT MONO (-6075 2725);
DISPLAY INVISIBLE (-6075 2725);
FORCEPROP 1 LAST BODY_TYPE PLUMBING
J 0
(-6075 2775);
DISPLAY 0.872340 (-6075 2775);
PAINT GREEN (-6075 2775);
DISPLAY INVISIBLE (-6075 2775);
FORCEPROP 1 LAST HDL_TAP TRUE
J 0
(-5750 2600);
DISPLAY 0.872340 (-5750 2600);
DISPLAY INVISIBLE (-5750 2600);
FORCEPROP 1 LAST PATH I278
J 0
(-6077 2725);
DISPLAY 0.872340 (-6077 2725);
PAINT GREEN (-6077 2725);
DISPLAY INVISIBLE (-6077 2725);
FORCEADD TAP..1
(-6075 2675);
FORCEPROP 3 LASTPIN (-6125 2675) SIG_NAME M_F_CPU0_SB_DQ<3>
J 0
(-6115 2685);
DISPLAY 0.659574 (-6115 2685);
PAINT MONO (-6115 2685);
DISPLAY INVISIBLE (-6115 2685);
FORCEPROP 1 LASTPIN (-6125 2675) BN 3
J 0
(-6137 2683);
DISPLAY 0.489362 (-6137 2683);
PAINT GREEN (-6137 2683);
FORCEPROP 2 LAST CDS_LIB mstr_standard
J 0
(-6075 2675);
DISPLAY 0.723404 (-6075 2675);
PAINT MONO (-6075 2675);
DISPLAY INVISIBLE (-6075 2675);
FORCEPROP 1 LAST BODY_TYPE PLUMBING
J 0
(-6075 2725);
DISPLAY 0.872340 (-6075 2725);
PAINT GREEN (-6075 2725);
DISPLAY INVISIBLE (-6075 2725);
FORCEPROP 1 LAST HDL_TAP TRUE
J 0
(-5750 2550);
DISPLAY 0.872340 (-5750 2550);
DISPLAY INVISIBLE (-5750 2550);
FORCEPROP 1 LAST PATH I279
J 0
(-6077 2675);
DISPLAY 0.872340 (-6077 2675);
PAINT GREEN (-6077 2675);
DISPLAY INVISIBLE (-6077 2675);
FORCEADD TAP..1
(-6075 2625);
FORCEPROP 3 LASTPIN (-6125 2625) SIG_NAME M_F_CPU0_SB_DQ<2>
J 0
(-6115 2635);
DISPLAY 0.659574 (-6115 2635);
PAINT MONO (-6115 2635);
DISPLAY INVISIBLE (-6115 2635);
FORCEPROP 1 LASTPIN (-6125 2625) BN 2
J 0
(-6137 2633);
DISPLAY 0.489362 (-6137 2633);
PAINT GREEN (-6137 2633);
FORCEPROP 2 LAST CDS_LIB mstr_standard
J 0
(-6075 2625);
DISPLAY 0.723404 (-6075 2625);
PAINT MONO (-6075 2625);
DISPLAY INVISIBLE (-6075 2625);
FORCEPROP 1 LAST BODY_TYPE PLUMBING
J 0
(-6075 2675);
DISPLAY 0.872340 (-6075 2675);
PAINT GREEN (-6075 2675);
DISPLAY INVISIBLE (-6075 2675);
FORCEPROP 1 LAST HDL_TAP TRUE
J 0
(-5750 2500);
DISPLAY 0.872340 (-5750 2500);
DISPLAY INVISIBLE (-5750 2500);
FORCEPROP 1 LAST PATH I280
J 0
(-6077 2625);
DISPLAY 0.872340 (-6077 2625);
PAINT GREEN (-6077 2625);
DISPLAY INVISIBLE (-6077 2625);
FORCEADD TAP..1
(-6075 2525);
FORCEPROP 3 LASTPIN (-6125 2525) SIG_NAME M_F_CPU0_SB_DQ<0>
J 0
(-6115 2535);
DISPLAY 0.659574 (-6115 2535);
PAINT MONO (-6115 2535);
DISPLAY INVISIBLE (-6115 2535);
FORCEPROP 1 LASTPIN (-6125 2525) BN 0
J 0
(-6137 2533);
DISPLAY 0.489362 (-6137 2533);
PAINT GREEN (-6137 2533);
FORCEPROP 2 LAST CDS_LIB mstr_standard
J 0
(-6075 2525);
DISPLAY 0.723404 (-6075 2525);
PAINT MONO (-6075 2525);
DISPLAY INVISIBLE (-6075 2525);
FORCEPROP 1 LAST BODY_TYPE PLUMBING
J 0
(-6075 2575);
DISPLAY 0.872340 (-6075 2575);
PAINT GREEN (-6075 2575);
DISPLAY INVISIBLE (-6075 2575);
FORCEPROP 1 LAST HDL_TAP TRUE
J 0
(-5750 2400);
DISPLAY 0.872340 (-5750 2400);
DISPLAY INVISIBLE (-5750 2400);
FORCEPROP 1 LAST PATH I281
J 0
(-6077 2525);
DISPLAY 0.872340 (-6077 2525);
PAINT GREEN (-6077 2525);
DISPLAY INVISIBLE (-6077 2525);
FORCEADD TAP..1
(-6075 2575);
FORCEPROP 3 LASTPIN (-6125 2575) SIG_NAME M_F_CPU0_SB_DQ<1>
J 0
(-6115 2585);
DISPLAY 0.659574 (-6115 2585);
PAINT MONO (-6115 2585);
DISPLAY INVISIBLE (-6115 2585);
FORCEPROP 1 LASTPIN (-6125 2575) BN 1
J 0
(-6137 2583);
DISPLAY 0.489362 (-6137 2583);
PAINT GREEN (-6137 2583);
FORCEPROP 2 LAST CDS_LIB mstr_standard
J 0
(-6075 2575);
DISPLAY 0.723404 (-6075 2575);
PAINT MONO (-6075 2575);
DISPLAY INVISIBLE (-6075 2575);
FORCEPROP 1 LAST BODY_TYPE PLUMBING
J 0
(-6075 2625);
DISPLAY 0.872340 (-6075 2625);
PAINT GREEN (-6075 2625);
DISPLAY INVISIBLE (-6075 2625);
FORCEPROP 1 LAST HDL_TAP TRUE
J 0
(-5750 2450);
DISPLAY 0.872340 (-5750 2450);
DISPLAY INVISIBLE (-5750 2450);
FORCEPROP 1 LAST PATH I282
J 0
(-6077 2575);
DISPLAY 0.872340 (-6077 2575);
PAINT GREEN (-6077 2575);
DISPLAY INVISIBLE (-6077 2575);
FORCEADD OFFPAGE..3
(-5450 4100);
FORCEPROP 2 LAST $XR0 15 
J 0
(-5236 4100);
DISPLAY 0.638298 (-5236 4100);
PAINT MONO (-5236 4100);
FORCEPROP 2 LAST CDS_LIB mstr_standard
J 0
(-5450 4100);
DISPLAY 0.723404 (-5450 4100);
PAINT MONO (-5450 4100);
DISPLAY INVISIBLE (-5450 4100);
FORCEPROP 1 LAST OFFPAGE TRUE
J 0
(-5125 3975);
DISPLAY 0.872340 (-5125 3975);
PAINT GREEN (-5125 3975);
DISPLAY INVISIBLE (-5125 3975);
FORCEPROP 1 LAST COMMENT_BODY TRUE
J 0
(-5500 4000);
DISPLAY 0.872340 (-5500 4000);
PAINT GREEN (-5500 4000);
DISPLAY INVISIBLE (-5500 4000);
FORCEPROP 2 LAST PATH I283
J 0
(-5125 4150);
DISPLAY 0.808511 (-5125 4150);
DISPLAY INVISIBLE (-5125 4150);
FORCEADD OFFPAGE..3
(-5450 5750);
FORCEPROP 2 LAST $XR0 15 
J 0
(-5236 5750);
DISPLAY 0.638298 (-5236 5750);
PAINT MONO (-5236 5750);
FORCEPROP 2 LAST CDS_LIB mstr_standard
J 0
(-5450 5750);
DISPLAY 0.723404 (-5450 5750);
PAINT MONO (-5450 5750);
DISPLAY INVISIBLE (-5450 5750);
FORCEPROP 1 LAST OFFPAGE TRUE
J 0
(-5125 5625);
DISPLAY 0.872340 (-5125 5625);
PAINT GREEN (-5125 5625);
DISPLAY INVISIBLE (-5125 5625);
FORCEPROP 1 LAST COMMENT_BODY TRUE
J 0
(-5500 5650);
DISPLAY 0.872340 (-5500 5650);
PAINT GREEN (-5500 5650);
DISPLAY INVISIBLE (-5500 5650);
FORCEPROP 2 LAST PATH I284
J 0
(-5225 5800);
DISPLAY 0.808511 (-5225 5800);
DISPLAY INVISIBLE (-5225 5800);
FORCEADD GND..1
(-6400 1375);
FORCEPROP 3 LASTPIN (-6400 1425) SIG_NAME GND\g
J 0
(-6390 1435);
DISPLAY 0.659574 (-6390 1435);
PAINT MONO (-6390 1435);
DISPLAY INVISIBLE (-6390 1435);
FORCEPROP 1 LAST SIZE 1B
J 0
(-6325 1325);
DISPLAY 0.851064 (-6325 1325);
PAINT GREEN (-6325 1325);
DISPLAY INVISIBLE (-6325 1325);
FORCEPROP 2 LAST CDS_LIB mstr_symbols
J 0
(-6400 1375);
DISPLAY 0.808511 (-6400 1375);
DISPLAY INVISIBLE (-6400 1375);
FORCEPROP 2 LAST BOM_COST MEM
J 0
(-6500 1450);
DISPLAY 0.808511 (-6500 1450);
DISPLAY INVISIBLE (-6500 1450);
FORCEPROP 1 LAST BODY_TYPE PLUMBING
J 0
(-6445 1332);
DISPLAY 0.340426 (-6445 1332);
PAINT GREEN (-6445 1332);
DISPLAY INVISIBLE (-6445 1332);
FORCEPROP 1 LAST PATH I332
J 0
(-6325 1375);
DISPLAY 0.872340 (-6325 1375);
PAINT GREEN (-6325 1375);
DISPLAY INVISIBLE (-6325 1375);
FORCEPROP 1 LAST VOLTAGE 0.0
J 0
(-6445 1332);
DISPLAY 0.723404 (-6445 1332);
PAINT SKYBLUE (-6445 1332);
DISPLAY INVISIBLE (-6445 1332);
FORCEPROP 1 LAST HDL_POWER GND
J 0
(-6400 1525);
DISPLAY 0.851064 (-6400 1525);
PAINT GREEN (-6400 1525);
DISPLAY INVISIBLE (-6400 1525);
FORCEADD OFFPAGE..5
(-7175 1775);
FORCEPROP 2 LAST $XR0 90 
J 0
(-7429 1775);
DISPLAY 0.638298 (-7429 1775);
PAINT MONO (-7429 1775);
FORCEPROP 2 LAST CDS_LIB mstr_standard
J 0
(-7175 1775);
DISPLAY 0.808511 (-7175 1775);
DISPLAY INVISIBLE (-7175 1775);
FORCEPROP 2 LAST BOM_COST MEM
J 0
(-7250 1850);
DISPLAY 0.808511 (-7250 1850);
DISPLAY INVISIBLE (-7250 1850);
FORCEPROP 1 LAST OFFPAGE TRUE
J 0
(-6850 1650);
DISPLAY 0.872340 (-6850 1650);
PAINT GREEN (-6850 1650);
DISPLAY INVISIBLE (-6850 1650);
FORCEPROP 1 LAST COMMENT_BODY TRUE
J 0
(-7075 1700);
DISPLAY 0.872340 (-7075 1700);
PAINT GREEN (-7075 1700);
DISPLAY INVISIBLE (-7075 1700);
FORCEPROP 2 LAST PATH I333
J 0
(-7125 1850);
DISPLAY 0.808511 (-7125 1850);
DISPLAY INVISIBLE (-7125 1850);
FORCEADD OFFPAGE..1
(-8375 3225);
FORCEPROP 2 LAST $XR0 90 
J 0
(-8626 3225);
DISPLAY 0.638298 (-8626 3225);
PAINT MONO (-8626 3225);
FORCEPROP 2 LAST CDS_LIB mstr_standard
J 0
(-8375 3225);
DISPLAY 0.808511 (-8375 3225);
DISPLAY INVISIBLE (-8375 3225);
FORCEPROP 1 LAST OFFPAGE TRUE
J 0
(-8050 3100);
DISPLAY 0.872340 (-8050 3100);
PAINT GREEN (-8050 3100);
DISPLAY INVISIBLE (-8050 3100);
FORCEPROP 1 LAST COMMENT_BODY TRUE
J 0
(-8250 3125);
DISPLAY 0.872340 (-8250 3125);
PAINT GREEN (-8250 3125);
DISPLAY INVISIBLE (-8250 3125);
FORCEPROP 2 LAST PATH I334
J 0
(-8325 3300);
DISPLAY 0.808511 (-8325 3300);
DISPLAY INVISIBLE (-8325 3300);
FORCEADD Q_RES..2
(-6400 1600);
FORCEPROP 1 LAST LOCATION R764
J 0
(-6355 1725);
DISPLAY 0.489362 (-6355 1725);
PAINT SKYBLUE (-6355 1725);
FORCEPROP 0 LAST $SEC 1
J 0
(-6350 1775);
DISPLAY 0.680851 (-6350 1775);
PAINT MONO (-6350 1775);
DISPLAY INVISIBLE (-6350 1775);
FORCEPROP 0 LAST CDS_SEC 1
J 0
(-6350 1775);
DISPLAY 1.021277 (-6350 1775);
DISPLAY INVISIBLE (-6350 1775);
FORCEPROP 1 LASTPIN (-6400 1700) $PN 1
J 0
(-6395 1662);
DISPLAY 0.489362 (-6395 1662);
PAINT MONO (-6395 1662);
FORCEPROP 1 LASTPIN (-6400 1500) $PN 2
J 0
(-6395 1510);
DISPLAY 0.489362 (-6395 1510);
PAINT MONO (-6395 1510);
FORCEPROP 1 LAST WATTAGE 1/16W
J 0
(-6360 1575);
DISPLAY 0.489362 (-6360 1575);
PAINT SKYBLUE (-6360 1575);
FORCEPROP 1 LAST MATERIAL CHIP
J 0
(-6360 1525);
DISPLAY 0.489362 (-6360 1525);
PAINT SKYBLUE (-6360 1525);
FORCEPROP 1 LAST TOLERANCE 1%
J 0
(-6355 1625);
DISPLAY 0.489362 (-6355 1625);
PAINT SKYBLUE (-6355 1625);
FORCEPROP 1 LAST VALUE 84.5K
J 0
(-6355 1675);
DISPLAY 0.489362 (-6355 1675);
PAINT SKYBLUE (-6355 1675);
FORCEPROP 1 LAST PART_NUMBER CS38452FB05
J 0
(-6360 1475);
DISPLAY 0.489362 (-6360 1475);
PAINT SKYBLUE (-6360 1475);
FORCEPROP 1 LAST PACK_TYPE 0402LF
J 0
(-6360 1425);
DISPLAY 0.489362 (-6360 1425);
PAINT SKYBLUE (-6360 1425);
FORCEPROP 2 LAST CDS_LIB pure_quanta
J 0
(-6400 1600);
DISPLAY INVISIBLE (-6400 1600);
FORCEPROP 1 LAST PATH I349
J 0
(-6350 1775);
DISPLAY 0.978723 (-6350 1775);
PAINT WHITE (-6350 1775);
DISPLAY INVISIBLE (-6350 1775);
FORCEADD SCONN288_DDR506112002KQ..1
(-6925 3975);
FORCEPROP 1 LAST LOCATION J23
J 0
(-7375 6050);
DISPLAY 0.468085 (-7375 6050);
PAINT SKYBLUE (-7375 6050);
FORCEPROP 0 LAST $SEC 1
J 0
(-7375 6200);
DISPLAY 0.680851 (-7375 6200);
PAINT MONO (-7375 6200);
DISPLAY INVISIBLE (-7375 6200);
FORCEPROP 2 LAST CDS_SEC 1
J 0
(-7375 6200);
DISPLAY 1.021277 (-7375 6200);
DISPLAY INVISIBLE (-7375 6200);
FORCEPROP 0 LASTPIN (-7525 3375) $PN 62
J 2
(-7535 3385);
DISPLAY 0.680851 (-7535 3385);
PAINT MONO (-7535 3385);
FORCEPROP 0 LASTPIN (-7525 5425) $PN 66
J 2
(-7535 5435);
DISPLAY 0.680851 (-7535 5435);
PAINT MONO (-7535 5435);
FORCEPROP 0 LASTPIN (-7525 5025) $PN 76
J 2
(-7535 5035);
DISPLAY 0.680851 (-7535 5035);
PAINT MONO (-7535 5035);
FORCEPROP 0 LASTPIN (-7525 5475) $PN 211
J 2
(-7535 5485);
DISPLAY 0.680851 (-7535 5485);
PAINT MONO (-7535 5485);
FORCEPROP 0 LASTPIN (-7525 5075) $PN 221
J 2
(-7535 5085);
DISPLAY 0.680851 (-7535 5085);
PAINT MONO (-7535 5085);
FORCEPROP 0 LASTPIN (-7525 5525) $PN 68
J 2
(-7535 5535);
DISPLAY 0.680851 (-7535 5535);
PAINT MONO (-7535 5535);
FORCEPROP 0 LASTPIN (-7525 5125) $PN 78
J 2
(-7535 5135);
DISPLAY 0.680851 (-7535 5135);
PAINT MONO (-7535 5135);
FORCEPROP 0 LASTPIN (-7525 5575) $PN 213
J 2
(-7535 5585);
DISPLAY 0.680851 (-7535 5585);
PAINT MONO (-7535 5585);
FORCEPROP 0 LASTPIN (-7525 5175) $PN 223
J 2
(-7535 5185);
DISPLAY 0.680851 (-7535 5185);
PAINT MONO (-7535 5185);
FORCEPROP 0 LASTPIN (-7525 5625) $PN 70
J 2
(-7535 5635);
DISPLAY 0.680851 (-7535 5635);
PAINT MONO (-7535 5635);
FORCEPROP 0 LASTPIN (-7525 5225) $PN 80
J 2
(-7535 5235);
DISPLAY 0.680851 (-7535 5235);
PAINT MONO (-7535 5235);
FORCEPROP 0 LASTPIN (-7525 5675) $PN 215
J 2
(-7535 5685);
DISPLAY 0.680851 (-7535 5685);
PAINT MONO (-7535 5685);
FORCEPROP 0 LASTPIN (-7525 5275) $PN 225
J 2
(-7535 5285);
DISPLAY 0.680851 (-7535 5285);
PAINT MONO (-7535 5285);
FORCEPROP 0 LASTPIN (-7525 5725) $PN 72
J 2
(-7535 5735);
DISPLAY 0.680851 (-7535 5735);
PAINT MONO (-7535 5735);
FORCEPROP 0 LASTPIN (-7525 5325) $PN 82
J 2
(-7535 5335);
DISPLAY 0.680851 (-7535 5335);
PAINT MONO (-7535 5335);
FORCEPROP 0 LASTPIN (-7525 3975) $PN 51
J 2
(-7535 3985);
DISPLAY 0.680851 (-7535 3985);
PAINT MONO (-7535 3985);
FORCEPROP 0 LASTPIN (-7525 3525) $PN 96
J 2
(-7535 3535);
DISPLAY 0.680851 (-7535 3535);
PAINT MONO (-7535 3535);
FORCEPROP 0 LASTPIN (-7525 4025) $PN 53
J 2
(-7535 4035);
DISPLAY 0.680851 (-7535 4035);
PAINT MONO (-7535 4035);
FORCEPROP 0 LASTPIN (-7525 3575) $PN 98
J 2
(-7535 3585);
DISPLAY 0.680851 (-7535 3585);
PAINT MONO (-7535 3585);
FORCEPROP 0 LASTPIN (-7525 4075) $PN 196
J 2
(-7535 4085);
DISPLAY 0.680851 (-7535 4085);
PAINT MONO (-7535 4085);
FORCEPROP 0 LASTPIN (-7525 3625) $PN 241
J 2
(-7535 3635);
DISPLAY 0.680851 (-7535 3635);
PAINT MONO (-7535 3635);
FORCEPROP 0 LASTPIN (-7525 4125) $PN 198
J 2
(-7535 4135);
DISPLAY 0.680851 (-7535 4135);
PAINT MONO (-7535 4135);
FORCEPROP 0 LASTPIN (-7525 3675) $PN 243
J 2
(-7535 3685);
DISPLAY 0.680851 (-7535 3685);
PAINT MONO (-7535 3685);
FORCEPROP 0 LASTPIN (-7525 4175) $PN 58
J 2
(-7535 4185);
DISPLAY 0.680851 (-7535 4185);
PAINT MONO (-7535 4185);
FORCEPROP 0 LASTPIN (-7525 3725) $PN 89
J 2
(-7535 3735);
DISPLAY 0.680851 (-7535 3735);
PAINT MONO (-7535 3735);
FORCEPROP 0 LASTPIN (-7525 4225) $PN 60
J 2
(-7535 4235);
DISPLAY 0.680851 (-7535 4235);
PAINT MONO (-7535 4235);
FORCEPROP 0 LASTPIN (-7525 3775) $PN 91
J 2
(-7535 3785);
DISPLAY 0.680851 (-7535 3785);
PAINT MONO (-7535 3785);
FORCEPROP 0 LASTPIN (-7525 4275) $PN 203
J 2
(-7535 4285);
DISPLAY 0.680851 (-7535 4285);
PAINT MONO (-7535 4285);
FORCEPROP 0 LASTPIN (-7525 3825) $PN 234
J 2
(-7535 3835);
DISPLAY 0.680851 (-7535 3835);
PAINT MONO (-7535 3835);
FORCEPROP 0 LASTPIN (-7525 4325) $PN 205
J 2
(-7535 4335);
DISPLAY 0.680851 (-7535 4335);
PAINT MONO (-7535 4335);
FORCEPROP 0 LASTPIN (-7525 3875) $PN 236
J 2
(-7535 3885);
DISPLAY 0.680851 (-7535 3885);
PAINT MONO (-7535 3885);
FORCEPROP 0 LASTPIN (-7525 4425) $PN 218
J 2
(-7535 4435);
DISPLAY 0.680851 (-7535 4435);
PAINT MONO (-7535 4435);
FORCEPROP 0 LASTPIN (-7525 4475) $PN 217
J 2
(-7535 4485);
DISPLAY 0.680851 (-7535 4485);
PAINT MONO (-7535 4485);
FORCEPROP 0 LASTPIN (-7525 4725) $PN 64
J 2
(-7535 4735);
DISPLAY 0.680851 (-7535 4735);
PAINT MONO (-7535 4735);
FORCEPROP 0 LASTPIN (-7525 4575) $PN 84
J 2
(-7535 4585);
DISPLAY 0.680851 (-7535 4585);
PAINT MONO (-7535 4585);
FORCEPROP 0 LASTPIN (-7525 4775) $PN 209
J 2
(-7535 4785);
DISPLAY 0.680851 (-7535 4785);
PAINT MONO (-7535 4785);
FORCEPROP 0 LASTPIN (-7525 4625) $PN 229
J 2
(-7535 4635);
DISPLAY 0.680851 (-7535 4635);
PAINT MONO (-7535 4635);
FORCEPROP 0 LASTPIN (-6325 4175) $PN 7
J 0
(-6315 4185);
DISPLAY 0.680851 (-6315 4185);
PAINT MONO (-6315 4185);
FORCEPROP 0 LASTPIN (-6325 2525) $PN 100
J 0
(-6315 2535);
DISPLAY 0.680851 (-6315 2535);
PAINT MONO (-6315 2535);
FORCEPROP 0 LASTPIN (-6325 4225) $PN 9
J 0
(-6315 4235);
DISPLAY 0.680851 (-6315 4235);
PAINT MONO (-6315 4235);
FORCEPROP 0 LASTPIN (-6325 2575) $PN 102
J 0
(-6315 2585);
DISPLAY 0.680851 (-6315 2585);
PAINT MONO (-6315 2585);
FORCEPROP 0 LASTPIN (-6325 4275) $PN 152
J 0
(-6315 4285);
DISPLAY 0.680851 (-6315 4285);
PAINT MONO (-6315 4285);
FORCEPROP 0 LASTPIN (-6325 2625) $PN 245
J 0
(-6315 2635);
DISPLAY 0.680851 (-6315 2635);
PAINT MONO (-6315 2635);
FORCEPROP 0 LASTPIN (-6325 4325) $PN 154
J 0
(-6315 4335);
DISPLAY 0.680851 (-6315 4335);
PAINT MONO (-6315 4335);
FORCEPROP 0 LASTPIN (-6325 2675) $PN 247
J 0
(-6315 2685);
DISPLAY 0.680851 (-6315 2685);
PAINT MONO (-6315 2685);
FORCEPROP 0 LASTPIN (-6325 4375) $PN 14
J 0
(-6315 4385);
DISPLAY 0.680851 (-6315 4385);
PAINT MONO (-6315 4385);
FORCEPROP 0 LASTPIN (-6325 2725) $PN 107
J 0
(-6315 2735);
DISPLAY 0.680851 (-6315 2735);
PAINT MONO (-6315 2735);
FORCEPROP 0 LASTPIN (-6325 4425) $PN 16
J 0
(-6315 4435);
DISPLAY 0.680851 (-6315 4435);
PAINT MONO (-6315 4435);
FORCEPROP 0 LASTPIN (-6325 2775) $PN 109
J 0
(-6315 2785);
DISPLAY 0.680851 (-6315 2785);
PAINT MONO (-6315 2785);
FORCEPROP 0 LASTPIN (-6325 4475) $PN 159
J 0
(-6315 4485);
DISPLAY 0.680851 (-6315 4485);
PAINT MONO (-6315 4485);
FORCEPROP 0 LASTPIN (-6325 2825) $PN 252
J 0
(-6315 2835);
DISPLAY 0.680851 (-6315 2835);
PAINT MONO (-6315 2835);
FORCEPROP 0 LASTPIN (-6325 4525) $PN 161
J 0
(-6315 4535);
DISPLAY 0.680851 (-6315 4535);
PAINT MONO (-6315 4535);
FORCEPROP 0 LASTPIN (-6325 2875) $PN 254
J 0
(-6315 2885);
DISPLAY 0.680851 (-6315 2885);
PAINT MONO (-6315 2885);
FORCEPROP 0 LASTPIN (-6325 4575) $PN 18
J 0
(-6315 4585);
DISPLAY 0.680851 (-6315 4585);
PAINT MONO (-6315 4585);
FORCEPROP 0 LASTPIN (-6325 2925) $PN 111
J 0
(-6315 2935);
DISPLAY 0.680851 (-6315 2935);
PAINT MONO (-6315 2935);
FORCEPROP 0 LASTPIN (-6325 4625) $PN 20
J 0
(-6315 4635);
DISPLAY 0.680851 (-6315 4635);
PAINT MONO (-6315 4635);
FORCEPROP 0 LASTPIN (-6325 2975) $PN 113
J 0
(-6315 2985);
DISPLAY 0.680851 (-6315 2985);
PAINT MONO (-6315 2985);
FORCEPROP 0 LASTPIN (-6325 4675) $PN 163
J 0
(-6315 4685);
DISPLAY 0.680851 (-6315 4685);
PAINT MONO (-6315 4685);
FORCEPROP 0 LASTPIN (-6325 3025) $PN 256
J 0
(-6315 3035);
DISPLAY 0.680851 (-6315 3035);
PAINT MONO (-6315 3035);
FORCEPROP 0 LASTPIN (-6325 4725) $PN 165
J 0
(-6315 4735);
DISPLAY 0.680851 (-6315 4735);
PAINT MONO (-6315 4735);
FORCEPROP 0 LASTPIN (-6325 3075) $PN 258
J 0
(-6315 3085);
DISPLAY 0.680851 (-6315 3085);
PAINT MONO (-6315 3085);
FORCEPROP 0 LASTPIN (-6325 4775) $PN 25
J 0
(-6315 4785);
DISPLAY 0.680851 (-6315 4785);
PAINT MONO (-6315 4785);
FORCEPROP 0 LASTPIN (-6325 3125) $PN 118
J 0
(-6315 3135);
DISPLAY 0.680851 (-6315 3135);
PAINT MONO (-6315 3135);
FORCEPROP 0 LASTPIN (-6325 4825) $PN 27
J 0
(-6315 4835);
DISPLAY 0.680851 (-6315 4835);
PAINT MONO (-6315 4835);
FORCEPROP 0 LASTPIN (-6325 3175) $PN 120
J 0
(-6315 3185);
DISPLAY 0.680851 (-6315 3185);
PAINT MONO (-6315 3185);
FORCEPROP 0 LASTPIN (-6325 4875) $PN 170
J 0
(-6315 4885);
DISPLAY 0.680851 (-6315 4885);
PAINT MONO (-6315 4885);
FORCEPROP 0 LASTPIN (-6325 3225) $PN 263
J 0
(-6315 3235);
DISPLAY 0.680851 (-6315 3235);
PAINT MONO (-6315 3235);
FORCEPROP 0 LASTPIN (-6325 4925) $PN 172
J 0
(-6315 4935);
DISPLAY 0.680851 (-6315 4935);
PAINT MONO (-6315 4935);
FORCEPROP 0 LASTPIN (-6325 3275) $PN 265
J 0
(-6315 3285);
DISPLAY 0.680851 (-6315 3285);
PAINT MONO (-6315 3285);
FORCEPROP 0 LASTPIN (-6325 4975) $PN 29
J 0
(-6315 4985);
DISPLAY 0.680851 (-6315 4985);
PAINT MONO (-6315 4985);
FORCEPROP 0 LASTPIN (-6325 3325) $PN 122
J 0
(-6315 3335);
DISPLAY 0.680851 (-6315 3335);
PAINT MONO (-6315 3335);
FORCEPROP 0 LASTPIN (-6325 5025) $PN 31
J 0
(-6315 5035);
DISPLAY 0.680851 (-6315 5035);
PAINT MONO (-6315 5035);
FORCEPROP 0 LASTPIN (-6325 3375) $PN 124
J 0
(-6315 3385);
DISPLAY 0.680851 (-6315 3385);
PAINT MONO (-6315 3385);
FORCEPROP 0 LASTPIN (-6325 5075) $PN 174
J 0
(-6315 5085);
DISPLAY 0.680851 (-6315 5085);
PAINT MONO (-6315 5085);
FORCEPROP 0 LASTPIN (-6325 3425) $PN 267
J 0
(-6315 3435);
DISPLAY 0.680851 (-6315 3435);
PAINT MONO (-6315 3435);
FORCEPROP 0 LASTPIN (-6325 5125) $PN 176
J 0
(-6315 5135);
DISPLAY 0.680851 (-6315 5135);
PAINT MONO (-6315 5135);
FORCEPROP 0 LASTPIN (-6325 3475) $PN 269
J 0
(-6315 3485);
DISPLAY 0.680851 (-6315 3485);
PAINT MONO (-6315 3485);
FORCEPROP 0 LASTPIN (-6325 5175) $PN 36
J 0
(-6315 5185);
DISPLAY 0.680851 (-6315 5185);
PAINT MONO (-6315 5185);
FORCEPROP 0 LASTPIN (-6325 3525) $PN 129
J 0
(-6315 3535);
DISPLAY 0.680851 (-6315 3535);
PAINT MONO (-6315 3535);
FORCEPROP 0 LASTPIN (-6325 5225) $PN 38
J 0
(-6315 5235);
DISPLAY 0.680851 (-6315 5235);
PAINT MONO (-6315 5235);
FORCEPROP 0 LASTPIN (-6325 3575) $PN 131
J 0
(-6315 3585);
DISPLAY 0.680851 (-6315 3585);
PAINT MONO (-6315 3585);
FORCEPROP 0 LASTPIN (-6325 5275) $PN 181
J 0
(-6315 5285);
DISPLAY 0.680851 (-6315 5285);
PAINT MONO (-6315 5285);
FORCEPROP 0 LASTPIN (-6325 3625) $PN 274
J 0
(-6315 3635);
DISPLAY 0.680851 (-6315 3635);
PAINT MONO (-6315 3635);
FORCEPROP 0 LASTPIN (-6325 5325) $PN 183
J 0
(-6315 5335);
DISPLAY 0.680851 (-6315 5335);
PAINT MONO (-6315 5335);
FORCEPROP 0 LASTPIN (-6325 3675) $PN 276
J 0
(-6315 3685);
DISPLAY 0.680851 (-6315 3685);
PAINT MONO (-6315 3685);
FORCEPROP 0 LASTPIN (-6325 5375) $PN 40
J 0
(-6315 5385);
DISPLAY 0.680851 (-6315 5385);
PAINT MONO (-6315 5385);
FORCEPROP 0 LASTPIN (-6325 3725) $PN 133
J 0
(-6315 3735);
DISPLAY 0.680851 (-6315 3735);
PAINT MONO (-6315 3735);
FORCEPROP 0 LASTPIN (-6325 5425) $PN 42
J 0
(-6315 5435);
DISPLAY 0.680851 (-6315 5435);
PAINT MONO (-6315 5435);
FORCEPROP 0 LASTPIN (-6325 3775) $PN 135
J 0
(-6315 3785);
DISPLAY 0.680851 (-6315 3785);
PAINT MONO (-6315 3785);
FORCEPROP 0 LASTPIN (-6325 5475) $PN 185
J 0
(-6315 5485);
DISPLAY 0.680851 (-6315 5485);
PAINT MONO (-6315 5485);
FORCEPROP 0 LASTPIN (-6325 3825) $PN 278
J 0
(-6315 3835);
DISPLAY 0.680851 (-6315 3835);
PAINT MONO (-6315 3835);
FORCEPROP 0 LASTPIN (-6325 5525) $PN 187
J 0
(-6315 5535);
DISPLAY 0.680851 (-6315 5535);
PAINT MONO (-6315 5535);
FORCEPROP 0 LASTPIN (-6325 3875) $PN 280
J 0
(-6315 3885);
DISPLAY 0.680851 (-6315 3885);
PAINT MONO (-6315 3885);
FORCEPROP 0 LASTPIN (-6325 5575) $PN 47
J 0
(-6315 5585);
DISPLAY 0.680851 (-6315 5585);
PAINT MONO (-6315 5585);
FORCEPROP 0 LASTPIN (-6325 3925) $PN 140
J 0
(-6315 3935);
DISPLAY 0.680851 (-6315 3935);
PAINT MONO (-6315 3935);
FORCEPROP 0 LASTPIN (-6325 5625) $PN 49
J 0
(-6315 5635);
DISPLAY 0.680851 (-6315 5635);
PAINT MONO (-6315 5635);
FORCEPROP 0 LASTPIN (-6325 3975) $PN 142
J 0
(-6315 3985);
DISPLAY 0.680851 (-6315 3985);
PAINT MONO (-6315 3985);
FORCEPROP 0 LASTPIN (-6325 5675) $PN 192
J 0
(-6315 5685);
DISPLAY 0.680851 (-6315 5685);
PAINT MONO (-6315 5685);
FORCEPROP 0 LASTPIN (-6325 4025) $PN 285
J 0
(-6315 4035);
DISPLAY 0.680851 (-6315 4035);
PAINT MONO (-6315 4035);
FORCEPROP 0 LASTPIN (-6325 5725) $PN 194
J 0
(-6315 5735);
DISPLAY 0.680851 (-6315 5735);
PAINT MONO (-6315 5735);
FORCEPROP 0 LASTPIN (-6325 4075) $PN 287
J 0
(-6315 4085);
DISPLAY 0.680851 (-6315 4085);
PAINT MONO (-6315 4085);
FORCEPROP 0 LASTPIN (-7525 3225) $PN 148
J 2
(-7535 3235);
DISPLAY 0.680851 (-7535 3235);
PAINT MONO (-7535 3235);
FORCEPROP 0 LASTPIN (-7525 3125) $PN 4
J 2
(-7535 3135);
DISPLAY 0.680851 (-7535 3135);
PAINT MONO (-7535 3135);
FORCEPROP 0 LASTPIN (-7525 3175) $PN 5
J 2
(-7535 3185);
DISPLAY 0.680851 (-7535 3185);
PAINT MONO (-7535 3185);
FORCEPROP 0 LASTPIN (-7525 2325) $PN 86
J 2
(-7535 2335);
DISPLAY 0.680851 (-7535 2335);
PAINT MONO (-7535 2335);
FORCEPROP 0 LASTPIN (-7525 2275) $PN 87
J 2
(-7535 2285);
DISPLAY 0.680851 (-7535 2285);
PAINT MONO (-7535 2285);
FORCEPROP 0 LASTPIN (-7525 4925) $PN 74
J 2
(-7535 4935);
DISPLAY 0.680851 (-7535 4935);
PAINT MONO (-7535 4935);
FORCEPROP 0 LASTPIN (-7525 4875) $PN 227
J 2
(-7535 4885);
DISPLAY 0.680851 (-7535 4885);
PAINT MONO (-7535 4885);
FORCEPROP 0 LASTPIN (-7525 2875) $PN 147
J 2
(-7535 2885);
DISPLAY 0.680851 (-7535 2885);
PAINT MONO (-7535 2885);
FORCEPROP 0 LASTPIN (-7525 3425) $PN 207
J 2
(-7535 3435);
DISPLAY 0.680851 (-7535 3435);
PAINT MONO (-7535 3435);
FORCEPROP 0 LASTPIN (-7525 2475) $PN 2
J 2
(-7535 2485);
DISPLAY 0.680851 (-7535 2485);
PAINT MONO (-7535 2485);
FORCEPROP 0 LASTPIN (-7525 2525) $PN 144
J 2
(-7535 2535);
DISPLAY 0.680851 (-7535 2535);
PAINT MONO (-7535 2535);
FORCEPROP 0 LASTPIN (-7525 2575) $PN 149
J 2
(-7535 2585);
DISPLAY 0.680851 (-7535 2585);
PAINT MONO (-7535 2585);
FORCEPROP 0 LASTPIN (-7525 2625) $PN 150
J 2
(-7535 2635);
DISPLAY 0.680851 (-7535 2635);
PAINT MONO (-7535 2635);
FORCEPROP 0 LASTPIN (-7525 2675) $PN 220
J 2
(-7535 2685);
DISPLAY 0.680851 (-7535 2685);
PAINT MONO (-7535 2685);
FORCEPROP 0 LASTPIN (-7525 2725) $PN 231
J 2
(-7535 2735);
DISPLAY 0.680851 (-7535 2735);
PAINT MONO (-7535 2735);
FORCEPROP 0 LASTPIN (-7525 2775) $PN 232
J 2
(-7535 2785);
DISPLAY 0.680851 (-7535 2785);
PAINT MONO (-7535 2785);
FORCEPROP 0 LASTPIN (-7525 3275) $PN 3
J 2
(-7535 3285);
DISPLAY 0.680851 (-7535 3285);
PAINT MONO (-7535 3285);
FORCEPROP 2 LAST VALUE SCONN288_DDR506112002KQ
J 0
(-7375 6100);
DISPLAY 0.489362 (-7375 6100);
PAINT SKYBLUE (-7375 6100);
FORCEPROP 2 LAST PART_TYPE SMLF
J 0
(-7375 6150);
DISPLAY 1.021277 (-7375 6150);
FORCEPROP 1 LAST MATERIAL IO
J 0
(-7375 5900);
DISPLAY 0.468085 (-7375 5900);
PAINT SKYBLUE (-7375 5900);
FORCEPROP 1 LAST PART_NUMBER DFHST8FS479
J 0
(-7375 5975);
DISPLAY 0.468085 (-7375 5975);
PAINT SKYBLUE (-7375 5975);
FORCEPROP 1 LAST CDS_LMAN_SYM_OUTLINE -450,1900,450,-1850
J 0
(-6925 3975);
DISPLAY 0.468085 (-6925 3975);
PAINT GREEN (-6925 3975);
DISPLAY INVISIBLE (-6925 3975);
FORCEPROP 1 LAST PATH I350
J 0
(-6925 3975);
DISPLAY 0.723404 (-6925 3975);
PAINT GREEN (-6925 3975);
DISPLAY INVISIBLE (-6925 3975);
FORCEPROP 1 LAST NEEDS_NO_SIZE TRUE
J 0
(-6925 3975);
DISPLAY 0.723404 (-6925 3975);
PAINT GREEN (-6925 3975);
DISPLAY INVISIBLE (-6925 3975);
FORCEPROP 2 LAST CDS_LIB pure_quanta
J 0
(-6925 3975);
DISPLAY INVISIBLE (-6925 3975);
FORCEADD SCONN288_DDR506112002KQ..3
(-1325 3950);
FORCEPROP 1 LAST LOCATION J23
J 0
(-1775 5925);
DISPLAY 0.468085 (-1775 5925);
PAINT SKYBLUE (-1775 5925);
FORCEPROP 0 LAST $SEC 3
J 0
(-1775 6075);
DISPLAY 0.680851 (-1775 6075);
PAINT MONO (-1775 6075);
DISPLAY INVISIBLE (-1775 6075);
FORCEPROP 2 LAST CDS_SEC 3
J 0
(-1775 6075);
DISPLAY 1.021277 (-1775 6075);
DISPLAY INVISIBLE (-1775 6075);
FORCEPROP 0 LASTPIN (-725 2350) $PN G1
J 0
(-715 2360);
DISPLAY 0.680851 (-715 2360);
PAINT MONO (-715 2360);
FORCEPROP 0 LASTPIN (-725 2300) $PN G2
J 0
(-715 2310);
DISPLAY 0.680851 (-715 2310);
PAINT MONO (-715 2310);
FORCEPROP 0 LASTPIN (-725 2250) $PN G3
J 0
(-715 2260);
DISPLAY 0.680851 (-715 2260);
PAINT MONO (-715 2260);
FORCEPROP 0 LASTPIN (-1925 5500) $PN 1
J 2
(-1935 5510);
DISPLAY 0.680851 (-1935 5510);
PAINT MONO (-1935 5510);
FORCEPROP 0 LASTPIN (-1925 5550) $PN 145
J 2
(-1935 5560);
DISPLAY 0.680851 (-1935 5560);
PAINT MONO (-1935 5560);
FORCEPROP 0 LASTPIN (-1925 5600) $PN 146
J 2
(-1935 5610);
DISPLAY 0.680851 (-1935 5610);
PAINT MONO (-1935 5610);
FORCEPROP 0 LASTPIN (-725 2450) $PN 6
J 0
(-715 2460);
DISPLAY 0.680851 (-715 2460);
PAINT MONO (-715 2460);
FORCEPROP 0 LASTPIN (-725 2500) $PN 8
J 0
(-715 2510);
DISPLAY 0.680851 (-715 2510);
PAINT MONO (-715 2510);
FORCEPROP 0 LASTPIN (-725 2550) $PN 10
J 0
(-715 2560);
DISPLAY 0.680851 (-715 2560);
PAINT MONO (-715 2560);
FORCEPROP 0 LASTPIN (-725 2600) $PN 13
J 0
(-715 2610);
DISPLAY 0.680851 (-715 2610);
PAINT MONO (-715 2610);
FORCEPROP 0 LASTPIN (-725 2650) $PN 15
J 0
(-715 2660);
DISPLAY 0.680851 (-715 2660);
PAINT MONO (-715 2660);
FORCEPROP 0 LASTPIN (-725 2700) $PN 17
J 0
(-715 2710);
DISPLAY 0.680851 (-715 2710);
PAINT MONO (-715 2710);
FORCEPROP 0 LASTPIN (-725 2750) $PN 19
J 0
(-715 2760);
DISPLAY 0.680851 (-715 2760);
PAINT MONO (-715 2760);
FORCEPROP 0 LASTPIN (-725 2800) $PN 21
J 0
(-715 2810);
DISPLAY 0.680851 (-715 2810);
PAINT MONO (-715 2810);
FORCEPROP 0 LASTPIN (-725 2850) $PN 24
J 0
(-715 2860);
DISPLAY 0.680851 (-715 2860);
PAINT MONO (-715 2860);
FORCEPROP 0 LASTPIN (-725 2900) $PN 26
J 0
(-715 2910);
DISPLAY 0.680851 (-715 2910);
PAINT MONO (-715 2910);
FORCEPROP 0 LASTPIN (-725 2950) $PN 28
J 0
(-715 2960);
DISPLAY 0.680851 (-715 2960);
PAINT MONO (-715 2960);
FORCEPROP 0 LASTPIN (-725 3000) $PN 30
J 0
(-715 3010);
DISPLAY 0.680851 (-715 3010);
PAINT MONO (-715 3010);
FORCEPROP 0 LASTPIN (-725 3050) $PN 32
J 0
(-715 3060);
DISPLAY 0.680851 (-715 3060);
PAINT MONO (-715 3060);
FORCEPROP 0 LASTPIN (-725 3100) $PN 35
J 0
(-715 3110);
DISPLAY 0.680851 (-715 3110);
PAINT MONO (-715 3110);
FORCEPROP 0 LASTPIN (-725 3150) $PN 37
J 0
(-715 3160);
DISPLAY 0.680851 (-715 3160);
PAINT MONO (-715 3160);
FORCEPROP 0 LASTPIN (-725 3200) $PN 39
J 0
(-715 3210);
DISPLAY 0.680851 (-715 3210);
PAINT MONO (-715 3210);
FORCEPROP 0 LASTPIN (-725 3250) $PN 41
J 0
(-715 3260);
DISPLAY 0.680851 (-715 3260);
PAINT MONO (-715 3260);
FORCEPROP 0 LASTPIN (-725 3300) $PN 43
J 0
(-715 3310);
DISPLAY 0.680851 (-715 3310);
PAINT MONO (-715 3310);
FORCEPROP 0 LASTPIN (-725 3350) $PN 46
J 0
(-715 3360);
DISPLAY 0.680851 (-715 3360);
PAINT MONO (-715 3360);
FORCEPROP 0 LASTPIN (-725 3400) $PN 48
J 0
(-715 3410);
DISPLAY 0.680851 (-715 3410);
PAINT MONO (-715 3410);
FORCEPROP 0 LASTPIN (-725 3450) $PN 50
J 0
(-715 3460);
DISPLAY 0.680851 (-715 3460);
PAINT MONO (-715 3460);
FORCEPROP 0 LASTPIN (-725 3500) $PN 52
J 0
(-715 3510);
DISPLAY 0.680851 (-715 3510);
PAINT MONO (-715 3510);
FORCEPROP 0 LASTPIN (-725 3550) $PN 54
J 0
(-715 3560);
DISPLAY 0.680851 (-715 3560);
PAINT MONO (-715 3560);
FORCEPROP 0 LASTPIN (-725 3600) $PN 57
J 0
(-715 3610);
DISPLAY 0.680851 (-715 3610);
PAINT MONO (-715 3610);
FORCEPROP 0 LASTPIN (-725 3650) $PN 59
J 0
(-715 3660);
DISPLAY 0.680851 (-715 3660);
PAINT MONO (-715 3660);
FORCEPROP 0 LASTPIN (-725 3700) $PN 61
J 0
(-715 3710);
DISPLAY 0.680851 (-715 3710);
PAINT MONO (-715 3710);
FORCEPROP 0 LASTPIN (-725 3750) $PN 63
J 0
(-715 3760);
DISPLAY 0.680851 (-715 3760);
PAINT MONO (-715 3760);
FORCEPROP 0 LASTPIN (-725 3800) $PN 65
J 0
(-715 3810);
DISPLAY 0.680851 (-715 3810);
PAINT MONO (-715 3810);
FORCEPROP 0 LASTPIN (-725 3850) $PN 67
J 0
(-715 3860);
DISPLAY 0.680851 (-715 3860);
PAINT MONO (-715 3860);
FORCEPROP 0 LASTPIN (-725 3900) $PN 69
J 0
(-715 3910);
DISPLAY 0.680851 (-715 3910);
PAINT MONO (-715 3910);
FORCEPROP 0 LASTPIN (-725 3950) $PN 71
J 0
(-715 3960);
DISPLAY 0.680851 (-715 3960);
PAINT MONO (-715 3960);
FORCEPROP 0 LASTPIN (-725 4000) $PN 73
J 0
(-715 4010);
DISPLAY 0.680851 (-715 4010);
PAINT MONO (-715 4010);
FORCEPROP 0 LASTPIN (-725 4050) $PN 75
J 0
(-715 4060);
DISPLAY 0.680851 (-715 4060);
PAINT MONO (-715 4060);
FORCEPROP 0 LASTPIN (-725 4100) $PN 77
J 0
(-715 4110);
DISPLAY 0.680851 (-715 4110);
PAINT MONO (-715 4110);
FORCEPROP 0 LASTPIN (-725 4150) $PN 79
J 0
(-715 4160);
DISPLAY 0.680851 (-715 4160);
PAINT MONO (-715 4160);
FORCEPROP 0 LASTPIN (-725 4200) $PN 81
J 0
(-715 4210);
DISPLAY 0.680851 (-715 4210);
PAINT MONO (-715 4210);
FORCEPROP 0 LASTPIN (-725 4250) $PN 83
J 0
(-715 4260);
DISPLAY 0.680851 (-715 4260);
PAINT MONO (-715 4260);
FORCEPROP 0 LASTPIN (-725 4300) $PN 85
J 0
(-715 4310);
DISPLAY 0.680851 (-715 4310);
PAINT MONO (-715 4310);
FORCEPROP 0 LASTPIN (-725 4350) $PN 88
J 0
(-715 4360);
DISPLAY 0.680851 (-715 4360);
PAINT MONO (-715 4360);
FORCEPROP 0 LASTPIN (-725 4400) $PN 90
J 0
(-715 4410);
DISPLAY 0.680851 (-715 4410);
PAINT MONO (-715 4410);
FORCEPROP 0 LASTPIN (-725 4450) $PN 92
J 0
(-715 4460);
DISPLAY 0.680851 (-715 4460);
PAINT MONO (-715 4460);
FORCEPROP 0 LASTPIN (-725 4500) $PN 95
J 0
(-715 4510);
DISPLAY 0.680851 (-715 4510);
PAINT MONO (-715 4510);
FORCEPROP 0 LASTPIN (-725 4550) $PN 97
J 0
(-715 4560);
DISPLAY 0.680851 (-715 4560);
PAINT MONO (-715 4560);
FORCEPROP 0 LASTPIN (-725 4600) $PN 99
J 0
(-715 4610);
DISPLAY 0.680851 (-715 4610);
PAINT MONO (-715 4610);
FORCEPROP 0 LASTPIN (-725 4650) $PN 101
J 0
(-715 4660);
DISPLAY 0.680851 (-715 4660);
PAINT MONO (-715 4660);
FORCEPROP 0 LASTPIN (-725 4700) $PN 103
J 0
(-715 4710);
DISPLAY 0.680851 (-715 4710);
PAINT MONO (-715 4710);
FORCEPROP 0 LASTPIN (-725 4750) $PN 106
J 0
(-715 4760);
DISPLAY 0.680851 (-715 4760);
PAINT MONO (-715 4760);
FORCEPROP 0 LASTPIN (-725 4800) $PN 108
J 0
(-715 4810);
DISPLAY 0.680851 (-715 4810);
PAINT MONO (-715 4810);
FORCEPROP 0 LASTPIN (-725 4850) $PN 110
J 0
(-715 4860);
DISPLAY 0.680851 (-715 4860);
PAINT MONO (-715 4860);
FORCEPROP 0 LASTPIN (-725 4900) $PN 112
J 0
(-715 4910);
DISPLAY 0.680851 (-715 4910);
PAINT MONO (-715 4910);
FORCEPROP 0 LASTPIN (-725 4950) $PN 114
J 0
(-715 4960);
DISPLAY 0.680851 (-715 4960);
PAINT MONO (-715 4960);
FORCEPROP 0 LASTPIN (-725 5000) $PN 117
J 0
(-715 5010);
DISPLAY 0.680851 (-715 5010);
PAINT MONO (-715 5010);
FORCEPROP 0 LASTPIN (-725 5050) $PN 119
J 0
(-715 5060);
DISPLAY 0.680851 (-715 5060);
PAINT MONO (-715 5060);
FORCEPROP 0 LASTPIN (-725 5100) $PN 121
J 0
(-715 5110);
DISPLAY 0.680851 (-715 5110);
PAINT MONO (-715 5110);
FORCEPROP 0 LASTPIN (-725 5150) $PN 123
J 0
(-715 5160);
DISPLAY 0.680851 (-715 5160);
PAINT MONO (-715 5160);
FORCEPROP 0 LASTPIN (-725 5200) $PN 125
J 0
(-715 5210);
DISPLAY 0.680851 (-715 5210);
PAINT MONO (-715 5210);
FORCEPROP 0 LASTPIN (-725 5250) $PN 128
J 0
(-715 5260);
DISPLAY 0.680851 (-715 5260);
PAINT MONO (-715 5260);
FORCEPROP 0 LASTPIN (-725 5300) $PN 130
J 0
(-715 5310);
DISPLAY 0.680851 (-715 5310);
PAINT MONO (-715 5310);
FORCEPROP 0 LASTPIN (-725 5350) $PN 132
J 0
(-715 5360);
DISPLAY 0.680851 (-715 5360);
PAINT MONO (-715 5360);
FORCEPROP 0 LASTPIN (-725 5400) $PN 134
J 0
(-715 5410);
DISPLAY 0.680851 (-715 5410);
PAINT MONO (-715 5410);
FORCEPROP 0 LASTPIN (-725 5450) $PN 136
J 0
(-715 5460);
DISPLAY 0.680851 (-715 5460);
PAINT MONO (-715 5460);
FORCEPROP 0 LASTPIN (-725 5500) $PN 139
J 0
(-715 5510);
DISPLAY 0.680851 (-715 5510);
PAINT MONO (-715 5510);
FORCEPROP 0 LASTPIN (-725 5550) $PN 141
J 0
(-715 5560);
DISPLAY 0.680851 (-715 5560);
PAINT MONO (-715 5560);
FORCEPROP 0 LASTPIN (-725 5600) $PN 143
J 0
(-715 5610);
DISPLAY 0.680851 (-715 5610);
PAINT MONO (-715 5610);
FORCEPROP 0 LASTPIN (-1925 2350) $PN 151
J 2
(-1935 2360);
DISPLAY 0.680851 (-1935 2360);
PAINT MONO (-1935 2360);
FORCEPROP 0 LASTPIN (-1925 2400) $PN 153
J 2
(-1935 2410);
DISPLAY 0.680851 (-1935 2410);
PAINT MONO (-1935 2410);
FORCEPROP 0 LASTPIN (-1925 2450) $PN 155
J 2
(-1935 2460);
DISPLAY 0.680851 (-1935 2460);
PAINT MONO (-1935 2460);
FORCEPROP 0 LASTPIN (-1925 2500) $PN 158
J 2
(-1935 2510);
DISPLAY 0.680851 (-1935 2510);
PAINT MONO (-1935 2510);
FORCEPROP 0 LASTPIN (-1925 2550) $PN 160
J 2
(-1935 2560);
DISPLAY 0.680851 (-1935 2560);
PAINT MONO (-1935 2560);
FORCEPROP 0 LASTPIN (-1925 2600) $PN 162
J 2
(-1935 2610);
DISPLAY 0.680851 (-1935 2610);
PAINT MONO (-1935 2610);
FORCEPROP 0 LASTPIN (-1925 2650) $PN 164
J 2
(-1935 2660);
DISPLAY 0.680851 (-1935 2660);
PAINT MONO (-1935 2660);
FORCEPROP 0 LASTPIN (-1925 2700) $PN 166
J 2
(-1935 2710);
DISPLAY 0.680851 (-1935 2710);
PAINT MONO (-1935 2710);
FORCEPROP 0 LASTPIN (-1925 2750) $PN 169
J 2
(-1935 2760);
DISPLAY 0.680851 (-1935 2760);
PAINT MONO (-1935 2760);
FORCEPROP 0 LASTPIN (-1925 2800) $PN 171
J 2
(-1935 2810);
DISPLAY 0.680851 (-1935 2810);
PAINT MONO (-1935 2810);
FORCEPROP 0 LASTPIN (-1925 2850) $PN 173
J 2
(-1935 2860);
DISPLAY 0.680851 (-1935 2860);
PAINT MONO (-1935 2860);
FORCEPROP 0 LASTPIN (-1925 2900) $PN 175
J 2
(-1935 2910);
DISPLAY 0.680851 (-1935 2910);
PAINT MONO (-1935 2910);
FORCEPROP 0 LASTPIN (-1925 2950) $PN 177
J 2
(-1935 2960);
DISPLAY 0.680851 (-1935 2960);
PAINT MONO (-1935 2960);
FORCEPROP 0 LASTPIN (-1925 3000) $PN 180
J 2
(-1935 3010);
DISPLAY 0.680851 (-1935 3010);
PAINT MONO (-1935 3010);
FORCEPROP 0 LASTPIN (-1925 3050) $PN 182
J 2
(-1935 3060);
DISPLAY 0.680851 (-1935 3060);
PAINT MONO (-1935 3060);
FORCEPROP 0 LASTPIN (-1925 3100) $PN 184
J 2
(-1935 3110);
DISPLAY 0.680851 (-1935 3110);
PAINT MONO (-1935 3110);
FORCEPROP 0 LASTPIN (-1925 3150) $PN 186
J 2
(-1935 3160);
DISPLAY 0.680851 (-1935 3160);
PAINT MONO (-1935 3160);
FORCEPROP 0 LASTPIN (-1925 3200) $PN 188
J 2
(-1935 3210);
DISPLAY 0.680851 (-1935 3210);
PAINT MONO (-1935 3210);
FORCEPROP 0 LASTPIN (-1925 3250) $PN 191
J 2
(-1935 3260);
DISPLAY 0.680851 (-1935 3260);
PAINT MONO (-1935 3260);
FORCEPROP 0 LASTPIN (-1925 3300) $PN 193
J 2
(-1935 3310);
DISPLAY 0.680851 (-1935 3310);
PAINT MONO (-1935 3310);
FORCEPROP 0 LASTPIN (-1925 3350) $PN 195
J 2
(-1935 3360);
DISPLAY 0.680851 (-1935 3360);
PAINT MONO (-1935 3360);
FORCEPROP 0 LASTPIN (-1925 3400) $PN 197
J 2
(-1935 3410);
DISPLAY 0.680851 (-1935 3410);
PAINT MONO (-1935 3410);
FORCEPROP 0 LASTPIN (-1925 3450) $PN 199
J 2
(-1935 3460);
DISPLAY 0.680851 (-1935 3460);
PAINT MONO (-1935 3460);
FORCEPROP 0 LASTPIN (-1925 3500) $PN 202
J 2
(-1935 3510);
DISPLAY 0.680851 (-1935 3510);
PAINT MONO (-1935 3510);
FORCEPROP 0 LASTPIN (-1925 3550) $PN 204
J 2
(-1935 3560);
DISPLAY 0.680851 (-1935 3560);
PAINT MONO (-1935 3560);
FORCEPROP 0 LASTPIN (-1925 3600) $PN 206
J 2
(-1935 3610);
DISPLAY 0.680851 (-1935 3610);
PAINT MONO (-1935 3610);
FORCEPROP 0 LASTPIN (-1925 3650) $PN 208
J 2
(-1935 3660);
DISPLAY 0.680851 (-1935 3660);
PAINT MONO (-1935 3660);
FORCEPROP 0 LASTPIN (-1925 3700) $PN 210
J 2
(-1935 3710);
DISPLAY 0.680851 (-1935 3710);
PAINT MONO (-1935 3710);
FORCEPROP 0 LASTPIN (-1925 3750) $PN 212
J 2
(-1935 3760);
DISPLAY 0.680851 (-1935 3760);
PAINT MONO (-1935 3760);
FORCEPROP 0 LASTPIN (-1925 3800) $PN 214
J 2
(-1935 3810);
DISPLAY 0.680851 (-1935 3810);
PAINT MONO (-1935 3810);
FORCEPROP 0 LASTPIN (-1925 3850) $PN 216
J 2
(-1935 3860);
DISPLAY 0.680851 (-1935 3860);
PAINT MONO (-1935 3860);
FORCEPROP 0 LASTPIN (-1925 3900) $PN 219
J 2
(-1935 3910);
DISPLAY 0.680851 (-1935 3910);
PAINT MONO (-1935 3910);
FORCEPROP 0 LASTPIN (-1925 3950) $PN 222
J 2
(-1935 3960);
DISPLAY 0.680851 (-1935 3960);
PAINT MONO (-1935 3960);
FORCEPROP 0 LASTPIN (-1925 4000) $PN 224
J 2
(-1935 4010);
DISPLAY 0.680851 (-1935 4010);
PAINT MONO (-1935 4010);
FORCEPROP 0 LASTPIN (-1925 4050) $PN 226
J 2
(-1935 4060);
DISPLAY 0.680851 (-1935 4060);
PAINT MONO (-1935 4060);
FORCEPROP 0 LASTPIN (-1925 4100) $PN 228
J 2
(-1935 4110);
DISPLAY 0.680851 (-1935 4110);
PAINT MONO (-1935 4110);
FORCEPROP 0 LASTPIN (-1925 4150) $PN 230
J 2
(-1935 4160);
DISPLAY 0.680851 (-1935 4160);
PAINT MONO (-1935 4160);
FORCEPROP 0 LASTPIN (-1925 4200) $PN 233
J 2
(-1935 4210);
DISPLAY 0.680851 (-1935 4210);
PAINT MONO (-1935 4210);
FORCEPROP 0 LASTPIN (-1925 4250) $PN 235
J 2
(-1935 4260);
DISPLAY 0.680851 (-1935 4260);
PAINT MONO (-1935 4260);
FORCEPROP 0 LASTPIN (-1925 4300) $PN 237
J 2
(-1935 4310);
DISPLAY 0.680851 (-1935 4310);
PAINT MONO (-1935 4310);
FORCEPROP 0 LASTPIN (-1925 4350) $PN 240
J 2
(-1935 4360);
DISPLAY 0.680851 (-1935 4360);
PAINT MONO (-1935 4360);
FORCEPROP 0 LASTPIN (-1925 4400) $PN 242
J 2
(-1935 4410);
DISPLAY 0.680851 (-1935 4410);
PAINT MONO (-1935 4410);
FORCEPROP 0 LASTPIN (-1925 4450) $PN 244
J 2
(-1935 4460);
DISPLAY 0.680851 (-1935 4460);
PAINT MONO (-1935 4460);
FORCEPROP 0 LASTPIN (-1925 4500) $PN 246
J 2
(-1935 4510);
DISPLAY 0.680851 (-1935 4510);
PAINT MONO (-1935 4510);
FORCEPROP 0 LASTPIN (-1925 4550) $PN 248
J 2
(-1935 4560);
DISPLAY 0.680851 (-1935 4560);
PAINT MONO (-1935 4560);
FORCEPROP 0 LASTPIN (-1925 4600) $PN 251
J 2
(-1935 4610);
DISPLAY 0.680851 (-1935 4610);
PAINT MONO (-1935 4610);
FORCEPROP 0 LASTPIN (-1925 4650) $PN 253
J 2
(-1935 4660);
DISPLAY 0.680851 (-1935 4660);
PAINT MONO (-1935 4660);
FORCEPROP 0 LASTPIN (-1925 4700) $PN 255
J 2
(-1935 4710);
DISPLAY 0.680851 (-1935 4710);
PAINT MONO (-1935 4710);
FORCEPROP 0 LASTPIN (-1925 4750) $PN 257
J 2
(-1935 4760);
DISPLAY 0.680851 (-1935 4760);
PAINT MONO (-1935 4760);
FORCEPROP 0 LASTPIN (-1925 4800) $PN 259
J 2
(-1935 4810);
DISPLAY 0.680851 (-1935 4810);
PAINT MONO (-1935 4810);
FORCEPROP 0 LASTPIN (-1925 4850) $PN 262
J 2
(-1935 4860);
DISPLAY 0.680851 (-1935 4860);
PAINT MONO (-1935 4860);
FORCEPROP 0 LASTPIN (-1925 4900) $PN 264
J 2
(-1935 4910);
DISPLAY 0.680851 (-1935 4910);
PAINT MONO (-1935 4910);
FORCEPROP 0 LASTPIN (-1925 4950) $PN 266
J 2
(-1935 4960);
DISPLAY 0.680851 (-1935 4960);
PAINT MONO (-1935 4960);
FORCEPROP 0 LASTPIN (-1925 5000) $PN 268
J 2
(-1935 5010);
DISPLAY 0.680851 (-1935 5010);
PAINT MONO (-1935 5010);
FORCEPROP 0 LASTPIN (-1925 5050) $PN 270
J 2
(-1935 5060);
DISPLAY 0.680851 (-1935 5060);
PAINT MONO (-1935 5060);
FORCEPROP 0 LASTPIN (-1925 5100) $PN 273
J 2
(-1935 5110);
DISPLAY 0.680851 (-1935 5110);
PAINT MONO (-1935 5110);
FORCEPROP 0 LASTPIN (-1925 5150) $PN 275
J 2
(-1935 5160);
DISPLAY 0.680851 (-1935 5160);
PAINT MONO (-1935 5160);
FORCEPROP 0 LASTPIN (-1925 5200) $PN 277
J 2
(-1935 5210);
DISPLAY 0.680851 (-1935 5210);
PAINT MONO (-1935 5210);
FORCEPROP 0 LASTPIN (-1925 5250) $PN 279
J 2
(-1935 5260);
DISPLAY 0.680851 (-1935 5260);
PAINT MONO (-1935 5260);
FORCEPROP 0 LASTPIN (-1925 5300) $PN 281
J 2
(-1935 5310);
DISPLAY 0.680851 (-1935 5310);
PAINT MONO (-1935 5310);
FORCEPROP 0 LASTPIN (-1925 5350) $PN 284
J 2
(-1935 5360);
DISPLAY 0.680851 (-1935 5360);
PAINT MONO (-1935 5360);
FORCEPROP 0 LASTPIN (-1925 5400) $PN 286
J 2
(-1935 5410);
DISPLAY 0.680851 (-1935 5410);
PAINT MONO (-1935 5410);
FORCEPROP 0 LASTPIN (-1925 5450) $PN 288
J 2
(-1935 5460);
DISPLAY 0.680851 (-1935 5460);
PAINT MONO (-1935 5460);
FORCEPROP 2 LAST VALUE SCONN288_DDR506112002KQ
J 0
(-1775 5975);
DISPLAY 0.489362 (-1775 5975);
PAINT SKYBLUE (-1775 5975);
FORCEPROP 2 LAST PART_TYPE SMLF
J 0
(-1775 6025);
DISPLAY 1.021277 (-1775 6025);
FORCEPROP 1 LAST MATERIAL IO
J 0
(-1775 5775);
DISPLAY 0.468085 (-1775 5775);
PAINT SKYBLUE (-1775 5775);
FORCEPROP 1 LAST PART_NUMBER DFHST8FS479
J 0
(-1775 5850);
DISPLAY 0.468085 (-1775 5850);
PAINT SKYBLUE (-1775 5850);
FORCEPROP 1 LAST CDS_LMAN_SYM_OUTLINE -450,1800,450,-1750
J 0
(-1325 3950);
DISPLAY 0.468085 (-1325 3950);
PAINT GREEN (-1325 3950);
DISPLAY INVISIBLE (-1325 3950);
FORCEPROP 1 LAST PATH I352
J 0
(-1325 3950);
DISPLAY 0.723404 (-1325 3950);
PAINT GREEN (-1325 3950);
DISPLAY INVISIBLE (-1325 3950);
FORCEPROP 1 LAST NEEDS_NO_SIZE TRUE
J 0
(-1325 3950);
DISPLAY 0.723404 (-1325 3950);
PAINT GREEN (-1325 3950);
DISPLAY INVISIBLE (-1325 3950);
FORCEPROP 2 LAST CDS_LIB pure_quanta
J 0
(-1325 3950);
DISPLAY INVISIBLE (-1325 3950);
FORCEADD OFFPAGE..5
(-8175 3375);
FORCEPROP 2 LAST $XR0 15 
J 0
(-8429 3375);
DISPLAY 0.638298 (-8429 3375);
PAINT MONO (-8429 3375);
FORCEPROP 2 LAST CDS_LIB mstr_standard
J 0
(-8175 3375);
DISPLAY INVISIBLE (-8175 3375);
FORCEPROP 1 LAST OFFPAGE TRUE
J 0
(-7850 3250);
DISPLAY 0.872340 (-7850 3250);
PAINT GREEN (-7850 3250);
DISPLAY INVISIBLE (-7850 3250);
FORCEPROP 1 LAST COMMENT_BODY TRUE
J 0
(-8075 3300);
DISPLAY 0.872340 (-8075 3300);
PAINT GREEN (-8075 3300);
DISPLAY INVISIBLE (-8075 3300);
FORCEPROP 2 LAST PATH I353
J 0
(-8125 3450);
DISPLAY 1.021277 (-8125 3450);
DISPLAY INVISIBLE (-8125 3450);
FORCEADD OFFPAGE..6
(-8375 3175);
FORCEPROP 2 LAST $XR5 136 
J 0
(-9134 3175);
DISPLAY 0.638298 (-9134 3175);
PAINT MONO (-9134 3175);
FORCEPROP 2 LAST $XR4 89 
J 0
(-9014 3175);
DISPLAY 0.638298 (-9014 3175);
PAINT MONO (-9014 3175);
FORCEPROP 2 LAST $XR3 88 
J 0
(-8924 3175);
DISPLAY 0.638298 (-8924 3175);
PAINT MONO (-8924 3175);
FORCEPROP 2 LAST $XR2 87 
J 0
(-8834 3175);
DISPLAY 0.638298 (-8834 3175);
PAINT MONO (-8834 3175);
FORCEPROP 2 LAST $XR1 86 
J 0
(-8744 3175);
DISPLAY 0.638298 (-8744 3175);
PAINT MONO (-8744 3175);
FORCEPROP 2 LAST $XR0 85 
J 0
(-8654 3175);
DISPLAY 0.638298 (-8654 3175);
PAINT MONO (-8654 3175);
FORCEPROP 2 LAST CDS_LIB mstr_standard
J 0
(-8375 3175);
DISPLAY 0.808511 (-8375 3175);
DISPLAY INVISIBLE (-8375 3175);
FORCEPROP 1 LAST OFFPAGE TRUE
J 0
(-8050 3050);
DISPLAY 0.872340 (-8050 3050);
PAINT GREEN (-8050 3050);
DISPLAY INVISIBLE (-8050 3050);
FORCEPROP 1 LAST COMMENT_BODY TRUE
J 0
(-8275 3100);
DISPLAY 0.872340 (-8275 3100);
PAINT GREEN (-8275 3100);
DISPLAY INVISIBLE (-8275 3100);
FORCEPROP 2 LAST PATH I355
J 0
(-8650 3225);
DISPLAY 1.021277 (-8650 3225);
DISPLAY INVISIBLE (-8650 3225);
FORCEADD Q_CAP..1
R 2
(-8650 3575);
FORCEPROP 1 LAST LOCATION C108
J 2
(-8700 3675);
DISPLAY 0.489362 (-8700 3675);
PAINT SKYBLUE (-8700 3675);
FORCEPROP 0 LAST $SEC 1
J 0
(-8700 3725);
DISPLAY 0.680851 (-8700 3725);
PAINT MONO (-8700 3725);
DISPLAY INVISIBLE (-8700 3725);
FORCEPROP 0 LAST CDS_SEC 1
J 0
(-8700 3725);
DISPLAY 1.021277 (-8700 3725);
DISPLAY INVISIBLE (-8700 3725);
FORCEPROP 1 LASTPIN (-8650 3675) $PN 1
J 2
(-8660 3655);
DISPLAY 0.489362 (-8660 3655);
PAINT MONO (-8660 3655);
FORCEPROP 1 LASTPIN (-8650 3475) $PN 2
J 2
(-8660 3455);
DISPLAY 0.489362 (-8660 3455);
PAINT MONO (-8660 3455);
FORCEPROP 1 LAST MATERIAL X7R
J 2
(-8700 3475);
DISPLAY 0.489362 (-8700 3475);
PAINT SKYBLUE (-8700 3475);
FORCEPROP 1 LAST VALUE 0.1UF
J 2
(-8700 3625);
DISPLAY 0.489362 (-8700 3625);
PAINT SKYBLUE (-8700 3625);
FORCEPROP 1 LAST TOLERANCE 10%
J 2
(-8700 3525);
DISPLAY 0.489362 (-8700 3525);
PAINT SKYBLUE (-8700 3525);
FORCEPROP 1 LAST VOLTAGE 25V
J 2
(-8700 3575);
DISPLAY 0.489362 (-8700 3575);
PAINT SKYBLUE (-8700 3575);
FORCEPROP 1 LAST PACK_TYPE 0402
J 2
(-8700 3375);
DISPLAY 0.489362 (-8700 3375);
PAINT SKYBLUE (-8700 3375);
FORCEPROP 1 LAST PART_NUMBER CH4104K1B00
J 2
(-8700 3425);
DISPLAY 0.489362 (-8700 3425);
PAINT SKYBLUE (-8700 3425);
FORCEPROP 2 LAST CDS_LIB pure_quanta
J 0
(-8650 3575);
DISPLAY INVISIBLE (-8650 3575);
FORCEPROP 0 LAST BOM_COST MEM
J 2
(-8705 3720);
DISPLAY 0.595745 (-8705 3720);
PAINT MONO (-8705 3720);
DISPLAY INVISIBLE (-8705 3720);
FORCEPROP 1 LAST PATH I361
J 2
(-8700 3725);
DISPLAY 0.978723 (-8700 3725);
PAINT WHITE (-8700 3725);
DISPLAY INVISIBLE (-8700 3725);
FORCEPROP 0 LAST ROOM MEM_CH_A_CPU0_DIMM1
J 2
(-8705 3720);
DISPLAY 0.595745 (-8705 3720);
PAINT RED (-8705 3720);
DISPLAY INVISIBLE (-8705 3720);
FORCEADD GND..1
(-8650 3350);
FORCEPROP 3 LASTPIN (-8650 3400) SIG_NAME GND\g
J 0
(-8640 3410);
DISPLAY 0.659574 (-8640 3410);
PAINT MONO (-8640 3410);
DISPLAY INVISIBLE (-8640 3410);
FORCEPROP 2 LAST CDS_LIB mstr_symbols
J 0
(-8650 3350);
DISPLAY 0.808511 (-8650 3350);
DISPLAY INVISIBLE (-8650 3350);
FORCEPROP 1 LAST SIZE 1B
J 0
(-8575 3300);
DISPLAY 0.723404 (-8575 3300);
PAINT GREEN (-8575 3300);
DISPLAY INVISIBLE (-8575 3300);
FORCEPROP 2 LAST BOM_COST MEM
J 0
(-8625 3475);
DISPLAY 0.659574 (-8625 3475);
DISPLAY INVISIBLE (-8625 3475);
FORCEPROP 1 LAST BODY_TYPE PLUMBING
J 0
(-8695 3307);
DISPLAY 0.276596 (-8695 3307);
PAINT GREEN (-8695 3307);
DISPLAY INVISIBLE (-8695 3307);
FORCEPROP 1 LAST PATH I362
J 0
(-8575 3350);
DISPLAY 0.872340 (-8575 3350);
PAINT AQUA (-8575 3350);
DISPLAY INVISIBLE (-8575 3350);
FORCEPROP 1 LAST VOLTAGE 0
J 0
(-8670 3445);
DISPLAY 0.829787 (-8670 3445);
PAINT SKYBLUE (-8670 3445);
DISPLAY INVISIBLE (-8670 3445);
FORCEPROP 2 LAST ROOM MEM_EFGH_DECOUPLING_CAPS
J 0
(-8625 3425);
DISPLAY 0.659574 (-8625 3425);
PAINT RED (-8625 3425);
DISPLAY INVISIBLE (-8625 3425);
FORCEPROP 1 LAST HDL_POWER GND
J 0
(-8650 3500);
DISPLAY 0.723404 (-8650 3500);
PAINT GREEN (-8650 3500);
DISPLAY INVISIBLE (-8650 3500);
FORCEADD OFFPAGE..6
(-9050 2475);
FORCEPROP 2 LAST $XR5 81 
J 0
(-9419 2511);
DISPLAY 0.638298 (-9419 2511);
PAINT MONO (-9419 2511);
FORCEPROP 2 LAST $XR4 89 
J 0
(-9329 2511);
DISPLAY 0.638298 (-9329 2511);
PAINT MONO (-9329 2511);
FORCEPROP 2 LAST $XR3 88 
J 0
(-9419 2439);
DISPLAY 0.638298 (-9419 2439);
PAINT MONO (-9419 2439);
FORCEPROP 2 LAST $XR2 87 
J 0
(-9329 2439);
DISPLAY 0.638298 (-9329 2439);
PAINT MONO (-9329 2439);
FORCEPROP 2 LAST $XR1 86 
J 0
(-9419 2475);
DISPLAY 0.638298 (-9419 2475);
PAINT MONO (-9419 2475);
FORCEPROP 2 LAST $XR0 85 
J 0
(-9329 2475);
DISPLAY 0.638298 (-9329 2475);
PAINT MONO (-9329 2475);
FORCEPROP 2 LAST CDS_LIB mstr_standard
J 0
(-9050 2475);
DISPLAY INVISIBLE (-9050 2475);
FORCEPROP 1 LAST OFFPAGE TRUE
J 0
(-8725 2350);
DISPLAY 0.872340 (-8725 2350);
PAINT GREEN (-8725 2350);
DISPLAY INVISIBLE (-8725 2350);
FORCEPROP 1 LAST COMMENT_BODY TRUE
J 0
(-8950 2400);
DISPLAY 0.872340 (-8950 2400);
PAINT GREEN (-8950 2400);
DISPLAY INVISIBLE (-8950 2400);
FORCEPROP 2 LAST PATH I363
J 0
(-9000 2550);
DISPLAY 1.021277 (-9000 2550);
DISPLAY INVISIBLE (-9000 2550);
FORCEADD Q_RES..1
R 2
(-8550 2475);
FORCEPROP 1 LAST LOCATION R296
J 2
(-8500 2525);
DISPLAY 0.489362 (-8500 2525);
PAINT SKYBLUE (-8500 2525);
FORCEPROP 0 LAST $SEC 1
J 0
(-8500 2575);
DISPLAY 0.680851 (-8500 2575);
PAINT MONO (-8500 2575);
DISPLAY INVISIBLE (-8500 2575);
FORCEPROP 0 LAST CDS_SEC 1
J 0
(-8500 2575);
DISPLAY 1.021277 (-8500 2575);
DISPLAY INVISIBLE (-8500 2575);
FORCEPROP 1 LASTPIN (-8450 2475) $PN 1
J 2
(-8462 2487);
DISPLAY 0.489362 (-8462 2487);
PAINT MONO (-8462 2487);
FORCEPROP 1 LASTPIN (-8650 2475) $PN 2
J 2
(-8612 2487);
DISPLAY 0.489362 (-8612 2487);
PAINT MONO (-8612 2487);
FORCEPROP 1 LAST VALUE 0
J 0
(-8550 2425);
DISPLAY 0.489362 (-8550 2425);
PAINT SKYBLUE (-8550 2425);
FORCEPROP 2 LAST CDS_LIB pure_quanta
J 0
(-8550 2475);
DISPLAY INVISIBLE (-8550 2475);
FORCEPROP 2 LAST BOM_COST MEM
J 0
(-8575 2625);
DISPLAY 0.744681 (-8575 2625);
PAINT WHITE (-8575 2625);
DISPLAY INVISIBLE (-8575 2625);
FORCEPROP 1 LAST PATH I364
J 2
(-8500 2625);
DISPLAY 0.978723 (-8500 2625);
PAINT WHITE (-8500 2625);
DISPLAY INVISIBLE (-8500 2625);
FORCEPROP 1 LAST WATTAGE 1/16W
J 0
(-8475 2400);
DISPLAY 0.489362 (-8475 2400);
PAINT SKYBLUE (-8475 2400);
DISPLAY INVISIBLE (-8475 2400);
FORCEPROP 1 LAST MATERIAL CHIP
J 0
(-8725 2450);
DISPLAY 0.489362 (-8725 2450);
PAINT SKYBLUE (-8725 2450);
DISPLAY INVISIBLE (-8725 2450);
FORCEPROP 1 LAST TOLERANCE 5%
J 2
(-8425 2450);
DISPLAY 0.489362 (-8425 2450);
PAINT SKYBLUE (-8425 2450);
DISPLAY INVISIBLE (-8425 2450);
FORCEPROP 1 LAST PART_NUMBER CS00002JB38
J 0
(-8650 2525);
DISPLAY 0.489362 (-8650 2525);
PAINT SKYBLUE (-8650 2525);
DISPLAY INVISIBLE (-8650 2525);
FORCEPROP 1 LAST PACK_TYPE 0402LF
J 0
(-8725 2400);
DISPLAY 0.489362 (-8725 2400);
PAINT SKYBLUE (-8725 2400);
DISPLAY INVISIBLE (-8725 2400);
FORCEPROP 2 LAST ROOM RST_CPU0_PLD_TO_DIMM
J 0
(-8575 2575);
DISPLAY 0.744681 (-8575 2575);
PAINT RED (-8575 2575);
DISPLAY INVISIBLE (-8575 2575);
FORCEADD Q_RES..2
(-8425 2625);
FORCEPROP 1 LAST LOCATION R94
J 0
(-8380 2750);
DISPLAY 0.489362 (-8380 2750);
PAINT SKYBLUE (-8380 2750);
FORCEPROP 0 LAST $SEC 1
J 0
(-8375 2800);
DISPLAY 0.680851 (-8375 2800);
PAINT MONO (-8375 2800);
DISPLAY INVISIBLE (-8375 2800);
FORCEPROP 0 LAST CDS_SEC 1
J 0
(-8375 2800);
DISPLAY 1.021277 (-8375 2800);
DISPLAY INVISIBLE (-8375 2800);
FORCEPROP 1 LASTPIN (-8425 2725) $PN 1
J 0
(-8420 2687);
DISPLAY 0.489362 (-8420 2687);
PAINT MONO (-8420 2687);
FORCEPROP 1 LASTPIN (-8425 2525) $PN 2
J 0
(-8420 2535);
DISPLAY 0.489362 (-8420 2535);
PAINT MONO (-8420 2535);
FORCEPROP 1 LAST WATTAGE 1/16W
J 0
(-8375 2650);
DISPLAY 0.489362 (-8375 2650);
PAINT SKYBLUE (-8375 2650);
FORCEPROP 1 LAST MATERIAL EMPTY
J 0
(-8375 2625);
DISPLAY 0.489362 (-8375 2625);
PAINT RED (-8375 2625);
FORCEPROP 1 LAST TOLERANCE 5%
J 0
(-8375 2675);
DISPLAY 0.489362 (-8375 2675);
PAINT SKYBLUE (-8375 2675);
FORCEPROP 1 LAST VALUE 1K
J 0
(-8380 2700);
DISPLAY 0.489362 (-8380 2700);
PAINT SKYBLUE (-8380 2700);
FORCEPROP 1 LAST PACK_TYPE 0402LF
J 0
(-8375 2575);
DISPLAY 0.489362 (-8375 2575);
PAINT SKYBLUE (-8375 2575);
FORCEPROP 2 LAST CDS_LIB pure_quanta
J 0
(-8425 2625);
DISPLAY INVISIBLE (-8425 2625);
FORCEPROP 2 LAST BOM_COST MEM
J 0
(-8375 2800);
DISPLAY 0.808511 (-8375 2800);
DISPLAY INVISIBLE (-8375 2800);
FORCEPROP 1 LAST PATH I365
J 0
(-8375 2800);
DISPLAY 0.978723 (-8375 2800);
PAINT WHITE (-8375 2800);
DISPLAY INVISIBLE (-8375 2800);
FORCEPROP 1 LAST PART_NUMBER TMP_QCS21002JB34
J 0
(-8375 2600);
DISPLAY 0.489362 (-8375 2600);
PAINT SKYBLUE (-8375 2600);
DISPLAY INVISIBLE (-8375 2600);
FORCEPROP 2 LAST ROOM MEM_CH_A_CPU0_DIMM1
J 0
(-8375 2850);
DISPLAY 0.808511 (-8375 2850);
PAINT RED (-8375 2850);
DISPLAY INVISIBLE (-8375 2850);
FORCEADD VCC_CORE..1
(-8425 2800);
FORCEPROP 3 LASTPIN (-8425 2750) SIG_NAME P3V3_STBY\g
J 0
(-8415 2760);
DISPLAY 0.659574 (-8415 2760);
PAINT MONO (-8415 2760);
DISPLAY INVISIBLE (-8415 2760);
FORCEPROP 1 LAST HDL_POWER P3V3_STBY
J 1
(-8425 2850);
DISPLAY 0.489362 (-8425 2850);
PAINT GREEN (-8425 2850);
FORCEPROP 2 LAST CDS_LIB mstr_symbols
J 0
(-8425 2800);
DISPLAY INVISIBLE (-8425 2800);
FORCEPROP 1 LAST PATH I366
J 0
(-8375 2825);
DISPLAY 0.872340 (-8375 2825);
PAINT AQUA (-8375 2825);
DISPLAY INVISIBLE (-8375 2825);
FORCEPROP 0 LAST VOLTAGE 3.3
J 0
(-8700 2950);
DISPLAY 1.021277 (-8700 2950);
PAINT SKYBLUE (-8700 2950);
DISPLAY INVISIBLE (-8700 2950);
FORCEPROP 2 LAST ROOM PVCCINFAON_CPU0_CTRL
J 0
(-8425 2900);
DISPLAY 0.808511 (-8425 2900);
PAINT RED (-8425 2900);
DISPLAY INVISIBLE (-8425 2900);
FORCEADD OFFPAGE..2
(-2575 4875);
FORCEPROP 2 LAST $XR0 15 
J 0
(-2386 4875);
DISPLAY 0.638298 (-2386 4875);
PAINT MONO (-2386 4875);
FORCEPROP 2 LAST CDS_LIB mstr_standard
J 0
(-2575 4875);
DISPLAY 0.723404 (-2575 4875);
PAINT MONO (-2575 4875);
DISPLAY INVISIBLE (-2575 4875);
FORCEPROP 1 LAST OFFPAGE TRUE
J 0
(-2250 4750);
DISPLAY 0.723404 (-2250 4750);
PAINT GREEN (-2250 4750);
DISPLAY INVISIBLE (-2250 4750);
FORCEPROP 1 LAST COMMENT_BODY TRUE
J 0
(-2620 4780);
DISPLAY 0.872340 (-2620 4780);
PAINT GREEN (-2620 4780);
DISPLAY INVISIBLE (-2620 4780);
FORCEPROP 2 LAST PATH I368
J 0
(-2375 4925);
DISPLAY 0.680851 (-2375 4925);
DISPLAY INVISIBLE (-2375 4925);
FORCEADD OFFPAGE..2
(-2575 4825);
FORCEPROP 2 LAST $XR0 15 
J 0
(-2386 4825);
DISPLAY 0.638298 (-2386 4825);
PAINT MONO (-2386 4825);
FORCEPROP 2 LAST CDS_LIB mstr_standard
J 0
(-2575 4825);
DISPLAY 0.723404 (-2575 4825);
PAINT MONO (-2575 4825);
DISPLAY INVISIBLE (-2575 4825);
FORCEPROP 1 LAST OFFPAGE TRUE
J 0
(-2250 4700);
DISPLAY 0.723404 (-2250 4700);
PAINT GREEN (-2250 4700);
DISPLAY INVISIBLE (-2250 4700);
FORCEPROP 1 LAST COMMENT_BODY TRUE
J 0
(-2620 4730);
DISPLAY 0.872340 (-2620 4730);
PAINT GREEN (-2620 4730);
DISPLAY INVISIBLE (-2620 4730);
FORCEPROP 2 LAST PATH I369
J 0
(-2375 4875);
DISPLAY 0.680851 (-2375 4875);
DISPLAY INVISIBLE (-2375 4875);
FORCEADD OFFPAGE..2
(-2575 3825);
FORCEPROP 2 LAST $XR0 15 
J 0
(-2386 3825);
DISPLAY 0.638298 (-2386 3825);
PAINT MONO (-2386 3825);
FORCEPROP 2 LAST CDS_LIB mstr_standard
J 0
(-2575 3825);
DISPLAY 0.723404 (-2575 3825);
PAINT MONO (-2575 3825);
DISPLAY INVISIBLE (-2575 3825);
FORCEPROP 1 LAST OFFPAGE TRUE
J 0
(-2250 3700);
DISPLAY 0.723404 (-2250 3700);
PAINT GREEN (-2250 3700);
DISPLAY INVISIBLE (-2250 3700);
FORCEPROP 1 LAST COMMENT_BODY TRUE
J 0
(-2620 3730);
DISPLAY 0.872340 (-2620 3730);
PAINT GREEN (-2620 3730);
DISPLAY INVISIBLE (-2620 3730);
FORCEPROP 2 LAST PATH I370
J 0
(-2375 3875);
DISPLAY 0.680851 (-2375 3875);
DISPLAY INVISIBLE (-2375 3875);
FORCEADD OFFPAGE..2
(-2575 3775);
FORCEPROP 2 LAST $XR0 15 
J 0
(-2386 3775);
DISPLAY 0.638298 (-2386 3775);
PAINT MONO (-2386 3775);
FORCEPROP 2 LAST CDS_LIB mstr_standard
J 0
(-2575 3775);
DISPLAY 0.723404 (-2575 3775);
PAINT MONO (-2575 3775);
DISPLAY INVISIBLE (-2575 3775);
FORCEPROP 1 LAST OFFPAGE TRUE
J 0
(-2250 3650);
DISPLAY 0.723404 (-2250 3650);
PAINT GREEN (-2250 3650);
DISPLAY INVISIBLE (-2250 3650);
FORCEPROP 1 LAST COMMENT_BODY TRUE
J 0
(-2620 3680);
DISPLAY 0.872340 (-2620 3680);
PAINT GREEN (-2620 3680);
DISPLAY INVISIBLE (-2620 3680);
FORCEPROP 2 LAST PATH I371
J 0
(-2375 3825);
DISPLAY 0.680851 (-2375 3825);
DISPLAY INVISIBLE (-2375 3825);
FORCEADD TAP..1
(-3375 4775);
FORCEPROP 3 LASTPIN (-3425 4775) SIG_NAME M_F_CPU0_SA_DQS_DN<9>
J 0
(-3415 4785);
DISPLAY 0.659574 (-3415 4785);
PAINT MONO (-3415 4785);
DISPLAY INVISIBLE (-3415 4785);
FORCEPROP 1 LASTPIN (-3425 4775) BN 9
J 0
(-3437 4783);
DISPLAY 0.489362 (-3437 4783);
PAINT GREEN (-3437 4783);
FORCEPROP 2 LAST CDS_LIB mstr_standard
J 0
(-3375 4775);
DISPLAY 0.723404 (-3375 4775);
PAINT MONO (-3375 4775);
DISPLAY INVISIBLE (-3375 4775);
FORCEPROP 1 LAST BODY_TYPE PLUMBING
J 0
(-3375 4825);
DISPLAY 0.872340 (-3375 4825);
PAINT GREEN (-3375 4825);
DISPLAY INVISIBLE (-3375 4825);
FORCEPROP 1 LAST HDL_TAP TRUE
J 0
(-3050 4650);
DISPLAY 0.872340 (-3050 4650);
DISPLAY INVISIBLE (-3050 4650);
FORCEPROP 1 LAST PATH I372
J 0
(-3377 4775);
DISPLAY 0.872340 (-3377 4775);
PAINT GREEN (-3377 4775);
DISPLAY INVISIBLE (-3377 4775);
FORCEADD TAP..1
(-3375 4675);
FORCEPROP 3 LASTPIN (-3425 4675) SIG_NAME M_F_CPU0_SA_DQS_DN<8>
J 0
(-3415 4685);
DISPLAY 0.659574 (-3415 4685);
PAINT MONO (-3415 4685);
DISPLAY INVISIBLE (-3415 4685);
FORCEPROP 1 LASTPIN (-3425 4675) BN 8
J 0
(-3437 4683);
DISPLAY 0.489362 (-3437 4683);
PAINT GREEN (-3437 4683);
FORCEPROP 2 LAST CDS_LIB mstr_standard
J 0
(-3375 4675);
DISPLAY 0.723404 (-3375 4675);
PAINT MONO (-3375 4675);
DISPLAY INVISIBLE (-3375 4675);
FORCEPROP 1 LAST BODY_TYPE PLUMBING
J 0
(-3375 4725);
DISPLAY 0.872340 (-3375 4725);
PAINT GREEN (-3375 4725);
DISPLAY INVISIBLE (-3375 4725);
FORCEPROP 1 LAST HDL_TAP TRUE
J 0
(-3050 4550);
DISPLAY 0.872340 (-3050 4550);
DISPLAY INVISIBLE (-3050 4550);
FORCEPROP 1 LAST PATH I373
J 0
(-3377 4675);
DISPLAY 0.872340 (-3377 4675);
PAINT GREEN (-3377 4675);
DISPLAY INVISIBLE (-3377 4675);
FORCEADD TAP..1
(-3375 4475);
FORCEPROP 3 LASTPIN (-3425 4475) SIG_NAME M_F_CPU0_SA_DQS_DN<6>
J 0
(-3415 4485);
DISPLAY 0.659574 (-3415 4485);
PAINT MONO (-3415 4485);
DISPLAY INVISIBLE (-3415 4485);
FORCEPROP 1 LASTPIN (-3425 4475) BN 6
J 0
(-3437 4483);
DISPLAY 0.489362 (-3437 4483);
PAINT GREEN (-3437 4483);
FORCEPROP 2 LAST CDS_LIB mstr_standard
J 0
(-3375 4475);
DISPLAY 0.723404 (-3375 4475);
PAINT MONO (-3375 4475);
DISPLAY INVISIBLE (-3375 4475);
FORCEPROP 1 LAST BODY_TYPE PLUMBING
J 0
(-3375 4525);
DISPLAY 0.872340 (-3375 4525);
PAINT GREEN (-3375 4525);
DISPLAY INVISIBLE (-3375 4525);
FORCEPROP 1 LAST HDL_TAP TRUE
J 0
(-3050 4350);
DISPLAY 0.872340 (-3050 4350);
DISPLAY INVISIBLE (-3050 4350);
FORCEPROP 1 LAST PATH I374
J 0
(-3377 4475);
DISPLAY 0.872340 (-3377 4475);
PAINT GREEN (-3377 4475);
DISPLAY INVISIBLE (-3377 4475);
FORCEADD TAP..1
(-3375 4575);
FORCEPROP 3 LASTPIN (-3425 4575) SIG_NAME M_F_CPU0_SA_DQS_DN<7>
J 0
(-3415 4585);
DISPLAY 0.659574 (-3415 4585);
PAINT MONO (-3415 4585);
DISPLAY INVISIBLE (-3415 4585);
FORCEPROP 1 LASTPIN (-3425 4575) BN 7
J 0
(-3437 4583);
DISPLAY 0.489362 (-3437 4583);
PAINT GREEN (-3437 4583);
FORCEPROP 2 LAST CDS_LIB mstr_standard
J 0
(-3375 4575);
DISPLAY 0.723404 (-3375 4575);
PAINT MONO (-3375 4575);
DISPLAY INVISIBLE (-3375 4575);
FORCEPROP 1 LAST BODY_TYPE PLUMBING
J 0
(-3375 4625);
DISPLAY 0.872340 (-3375 4625);
PAINT GREEN (-3375 4625);
DISPLAY INVISIBLE (-3375 4625);
FORCEPROP 1 LAST HDL_TAP TRUE
J 0
(-3050 4450);
DISPLAY 0.872340 (-3050 4450);
DISPLAY INVISIBLE (-3050 4450);
FORCEPROP 1 LAST PATH I375
J 0
(-3377 4575);
DISPLAY 0.872340 (-3377 4575);
PAINT GREEN (-3377 4575);
DISPLAY INVISIBLE (-3377 4575);
FORCEADD TAP..1
(-3375 4375);
FORCEPROP 3 LASTPIN (-3425 4375) SIG_NAME M_F_CPU0_SA_DQS_DN<5>
J 0
(-3415 4385);
DISPLAY 0.659574 (-3415 4385);
PAINT MONO (-3415 4385);
DISPLAY INVISIBLE (-3415 4385);
FORCEPROP 1 LASTPIN (-3425 4375) BN 5
J 0
(-3437 4383);
DISPLAY 0.489362 (-3437 4383);
PAINT GREEN (-3437 4383);
FORCEPROP 2 LAST CDS_LIB mstr_standard
J 0
(-3375 4375);
DISPLAY 0.723404 (-3375 4375);
PAINT MONO (-3375 4375);
DISPLAY INVISIBLE (-3375 4375);
FORCEPROP 1 LAST BODY_TYPE PLUMBING
J 0
(-3375 4425);
DISPLAY 0.872340 (-3375 4425);
PAINT GREEN (-3375 4425);
DISPLAY INVISIBLE (-3375 4425);
FORCEPROP 1 LAST HDL_TAP TRUE
J 0
(-3050 4250);
DISPLAY 0.872340 (-3050 4250);
DISPLAY INVISIBLE (-3050 4250);
FORCEPROP 1 LAST PATH I376
J 0
(-3377 4375);
DISPLAY 0.872340 (-3377 4375);
PAINT GREEN (-3377 4375);
DISPLAY INVISIBLE (-3377 4375);
FORCEADD TAP..1
(-3575 4725);
FORCEPROP 3 LASTPIN (-3625 4725) SIG_NAME M_F_CPU0_SA_DQS_DP<8>
J 0
(-3615 4735);
DISPLAY 0.659574 (-3615 4735);
PAINT MONO (-3615 4735);
DISPLAY INVISIBLE (-3615 4735);
FORCEPROP 1 LASTPIN (-3625 4725) BN 8
J 0
(-3637 4733);
DISPLAY 0.489362 (-3637 4733);
PAINT GREEN (-3637 4733);
FORCEPROP 2 LAST CDS_LIB mstr_standard
J 0
(-3575 4725);
DISPLAY 0.723404 (-3575 4725);
PAINT MONO (-3575 4725);
DISPLAY INVISIBLE (-3575 4725);
FORCEPROP 1 LAST BODY_TYPE PLUMBING
J 0
(-3575 4775);
DISPLAY 0.872340 (-3575 4775);
PAINT GREEN (-3575 4775);
DISPLAY INVISIBLE (-3575 4775);
FORCEPROP 1 LAST HDL_TAP TRUE
J 0
(-3250 4600);
DISPLAY 0.872340 (-3250 4600);
DISPLAY INVISIBLE (-3250 4600);
FORCEPROP 1 LAST PATH I377
J 0
(-3577 4725);
DISPLAY 0.872340 (-3577 4725);
PAINT GREEN (-3577 4725);
DISPLAY INVISIBLE (-3577 4725);
FORCEADD TAP..1
(-3575 4825);
FORCEPROP 3 LASTPIN (-3625 4825) SIG_NAME M_F_CPU0_SA_DQS_DP<9>
J 0
(-3615 4835);
DISPLAY 0.659574 (-3615 4835);
PAINT MONO (-3615 4835);
DISPLAY INVISIBLE (-3615 4835);
FORCEPROP 1 LASTPIN (-3625 4825) BN 9
J 0
(-3637 4833);
DISPLAY 0.489362 (-3637 4833);
PAINT GREEN (-3637 4833);
FORCEPROP 2 LAST CDS_LIB mstr_standard
J 0
(-3575 4825);
DISPLAY 0.723404 (-3575 4825);
PAINT MONO (-3575 4825);
DISPLAY INVISIBLE (-3575 4825);
FORCEPROP 1 LAST BODY_TYPE PLUMBING
J 0
(-3575 4875);
DISPLAY 0.872340 (-3575 4875);
PAINT GREEN (-3575 4875);
DISPLAY INVISIBLE (-3575 4875);
FORCEPROP 1 LAST HDL_TAP TRUE
J 0
(-3250 4700);
DISPLAY 0.872340 (-3250 4700);
DISPLAY INVISIBLE (-3250 4700);
FORCEPROP 1 LAST PATH I378
J 0
(-3577 4825);
DISPLAY 0.872340 (-3577 4825);
PAINT GREEN (-3577 4825);
DISPLAY INVISIBLE (-3577 4825);
FORCEADD TAP..1
(-3575 4625);
FORCEPROP 3 LASTPIN (-3625 4625) SIG_NAME M_F_CPU0_SA_DQS_DP<7>
J 0
(-3615 4635);
DISPLAY 0.659574 (-3615 4635);
PAINT MONO (-3615 4635);
DISPLAY INVISIBLE (-3615 4635);
FORCEPROP 1 LASTPIN (-3625 4625) BN 7
J 0
(-3637 4633);
DISPLAY 0.489362 (-3637 4633);
PAINT GREEN (-3637 4633);
FORCEPROP 2 LAST CDS_LIB mstr_standard
J 0
(-3575 4625);
DISPLAY 0.723404 (-3575 4625);
PAINT MONO (-3575 4625);
DISPLAY INVISIBLE (-3575 4625);
FORCEPROP 1 LAST BODY_TYPE PLUMBING
J 0
(-3575 4675);
DISPLAY 0.872340 (-3575 4675);
PAINT GREEN (-3575 4675);
DISPLAY INVISIBLE (-3575 4675);
FORCEPROP 1 LAST HDL_TAP TRUE
J 0
(-3250 4500);
DISPLAY 0.872340 (-3250 4500);
DISPLAY INVISIBLE (-3250 4500);
FORCEPROP 1 LAST PATH I379
J 0
(-3577 4625);
DISPLAY 0.872340 (-3577 4625);
PAINT GREEN (-3577 4625);
DISPLAY INVISIBLE (-3577 4625);
FORCEADD TAP..1
(-3575 4525);
FORCEPROP 3 LASTPIN (-3625 4525) SIG_NAME M_F_CPU0_SA_DQS_DP<6>
J 0
(-3615 4535);
DISPLAY 0.659574 (-3615 4535);
PAINT MONO (-3615 4535);
DISPLAY INVISIBLE (-3615 4535);
FORCEPROP 1 LASTPIN (-3625 4525) BN 6
J 0
(-3637 4533);
DISPLAY 0.489362 (-3637 4533);
PAINT GREEN (-3637 4533);
FORCEPROP 2 LAST CDS_LIB mstr_standard
J 0
(-3575 4525);
DISPLAY 0.723404 (-3575 4525);
PAINT MONO (-3575 4525);
DISPLAY INVISIBLE (-3575 4525);
FORCEPROP 1 LAST BODY_TYPE PLUMBING
J 0
(-3575 4575);
DISPLAY 0.872340 (-3575 4575);
PAINT GREEN (-3575 4575);
DISPLAY INVISIBLE (-3575 4575);
FORCEPROP 1 LAST HDL_TAP TRUE
J 0
(-3250 4400);
DISPLAY 0.872340 (-3250 4400);
DISPLAY INVISIBLE (-3250 4400);
FORCEPROP 1 LAST PATH I380
J 0
(-3577 4525);
DISPLAY 0.872340 (-3577 4525);
PAINT GREEN (-3577 4525);
DISPLAY INVISIBLE (-3577 4525);
FORCEADD TAP..1
(-3575 4425);
FORCEPROP 3 LASTPIN (-3625 4425) SIG_NAME M_F_CPU0_SA_DQS_DP<5>
J 0
(-3615 4435);
DISPLAY 0.659574 (-3615 4435);
PAINT MONO (-3615 4435);
DISPLAY INVISIBLE (-3615 4435);
FORCEPROP 1 LASTPIN (-3625 4425) BN 5
J 0
(-3637 4433);
DISPLAY 0.489362 (-3637 4433);
PAINT GREEN (-3637 4433);
FORCEPROP 2 LAST CDS_LIB mstr_standard
J 0
(-3575 4425);
DISPLAY 0.723404 (-3575 4425);
PAINT MONO (-3575 4425);
DISPLAY INVISIBLE (-3575 4425);
FORCEPROP 1 LAST BODY_TYPE PLUMBING
J 0
(-3575 4475);
DISPLAY 0.872340 (-3575 4475);
PAINT GREEN (-3575 4475);
DISPLAY INVISIBLE (-3575 4475);
FORCEPROP 1 LAST HDL_TAP TRUE
J 0
(-3250 4300);
DISPLAY 0.872340 (-3250 4300);
DISPLAY INVISIBLE (-3250 4300);
FORCEPROP 1 LAST PATH I381
J 0
(-3577 4425);
DISPLAY 0.872340 (-3577 4425);
PAINT GREEN (-3577 4425);
DISPLAY INVISIBLE (-3577 4425);
FORCEADD TAP..1
(-3375 4275);
FORCEPROP 3 LASTPIN (-3425 4275) SIG_NAME M_F_CPU0_SA_DQS_DN<4>
J 0
(-3415 4285);
DISPLAY 0.659574 (-3415 4285);
PAINT MONO (-3415 4285);
DISPLAY INVISIBLE (-3415 4285);
FORCEPROP 1 LASTPIN (-3425 4275) BN 4
J 0
(-3437 4283);
DISPLAY 0.489362 (-3437 4283);
PAINT GREEN (-3437 4283);
FORCEPROP 2 LAST CDS_LIB mstr_standard
J 0
(-3375 4275);
DISPLAY 0.723404 (-3375 4275);
PAINT MONO (-3375 4275);
DISPLAY INVISIBLE (-3375 4275);
FORCEPROP 1 LAST BODY_TYPE PLUMBING
J 0
(-3375 4325);
DISPLAY 0.872340 (-3375 4325);
PAINT GREEN (-3375 4325);
DISPLAY INVISIBLE (-3375 4325);
FORCEPROP 1 LAST HDL_TAP TRUE
J 0
(-3050 4150);
DISPLAY 0.872340 (-3050 4150);
DISPLAY INVISIBLE (-3050 4150);
FORCEPROP 1 LAST PATH I382
J 0
(-3377 4275);
DISPLAY 0.872340 (-3377 4275);
PAINT GREEN (-3377 4275);
DISPLAY INVISIBLE (-3377 4275);
FORCEADD TAP..1
(-3375 4175);
FORCEPROP 3 LASTPIN (-3425 4175) SIG_NAME M_F_CPU0_SA_DQS_DN<3>
J 0
(-3415 4185);
DISPLAY 0.659574 (-3415 4185);
PAINT MONO (-3415 4185);
DISPLAY INVISIBLE (-3415 4185);
FORCEPROP 1 LASTPIN (-3425 4175) BN 3
J 0
(-3437 4183);
DISPLAY 0.489362 (-3437 4183);
PAINT GREEN (-3437 4183);
FORCEPROP 2 LAST CDS_LIB mstr_standard
J 0
(-3375 4175);
DISPLAY 0.723404 (-3375 4175);
PAINT MONO (-3375 4175);
DISPLAY INVISIBLE (-3375 4175);
FORCEPROP 1 LAST BODY_TYPE PLUMBING
J 0
(-3375 4225);
DISPLAY 0.872340 (-3375 4225);
PAINT GREEN (-3375 4225);
DISPLAY INVISIBLE (-3375 4225);
FORCEPROP 1 LAST HDL_TAP TRUE
J 0
(-3050 4050);
DISPLAY 0.872340 (-3050 4050);
DISPLAY INVISIBLE (-3050 4050);
FORCEPROP 1 LAST PATH I383
J 0
(-3377 4175);
DISPLAY 0.872340 (-3377 4175);
PAINT GREEN (-3377 4175);
DISPLAY INVISIBLE (-3377 4175);
FORCEADD TAP..1
(-3375 4075);
FORCEPROP 3 LASTPIN (-3425 4075) SIG_NAME M_F_CPU0_SA_DQS_DN<2>
J 0
(-3415 4085);
DISPLAY 0.659574 (-3415 4085);
PAINT MONO (-3415 4085);
DISPLAY INVISIBLE (-3415 4085);
FORCEPROP 1 LASTPIN (-3425 4075) BN 2
J 0
(-3437 4083);
DISPLAY 0.489362 (-3437 4083);
PAINT GREEN (-3437 4083);
FORCEPROP 2 LAST CDS_LIB mstr_standard
J 0
(-3375 4075);
DISPLAY 0.723404 (-3375 4075);
PAINT MONO (-3375 4075);
DISPLAY INVISIBLE (-3375 4075);
FORCEPROP 1 LAST BODY_TYPE PLUMBING
J 0
(-3375 4125);
DISPLAY 0.872340 (-3375 4125);
PAINT GREEN (-3375 4125);
DISPLAY INVISIBLE (-3375 4125);
FORCEPROP 1 LAST HDL_TAP TRUE
J 0
(-3050 3950);
DISPLAY 0.872340 (-3050 3950);
DISPLAY INVISIBLE (-3050 3950);
FORCEPROP 1 LAST PATH I384
J 0
(-3377 4075);
DISPLAY 0.872340 (-3377 4075);
PAINT GREEN (-3377 4075);
DISPLAY INVISIBLE (-3377 4075);
FORCEADD TAP..1
(-3375 3975);
FORCEPROP 3 LASTPIN (-3425 3975) SIG_NAME M_F_CPU0_SA_DQS_DN<1>
J 0
(-3415 3985);
DISPLAY 0.659574 (-3415 3985);
PAINT MONO (-3415 3985);
DISPLAY INVISIBLE (-3415 3985);
FORCEPROP 1 LASTPIN (-3425 3975) BN 1
J 0
(-3437 3983);
DISPLAY 0.489362 (-3437 3983);
PAINT GREEN (-3437 3983);
FORCEPROP 2 LAST CDS_LIB mstr_standard
J 0
(-3375 3975);
DISPLAY 0.723404 (-3375 3975);
PAINT MONO (-3375 3975);
DISPLAY INVISIBLE (-3375 3975);
FORCEPROP 1 LAST BODY_TYPE PLUMBING
J 0
(-3375 4025);
DISPLAY 0.872340 (-3375 4025);
PAINT GREEN (-3375 4025);
DISPLAY INVISIBLE (-3375 4025);
FORCEPROP 1 LAST HDL_TAP TRUE
J 0
(-3050 3850);
DISPLAY 0.872340 (-3050 3850);
DISPLAY INVISIBLE (-3050 3850);
FORCEPROP 1 LAST PATH I385
J 0
(-3377 3975);
DISPLAY 0.872340 (-3377 3975);
PAINT GREEN (-3377 3975);
DISPLAY INVISIBLE (-3377 3975);
FORCEADD TAP..1
(-3375 3875);
FORCEPROP 3 LASTPIN (-3425 3875) SIG_NAME M_F_CPU0_SA_DQS_DN<0>
J 0
(-3415 3885);
DISPLAY 0.659574 (-3415 3885);
PAINT MONO (-3415 3885);
DISPLAY INVISIBLE (-3415 3885);
FORCEPROP 1 LASTPIN (-3425 3875) BN 0
J 0
(-3437 3883);
DISPLAY 0.489362 (-3437 3883);
PAINT GREEN (-3437 3883);
FORCEPROP 2 LAST CDS_LIB mstr_standard
J 0
(-3375 3875);
DISPLAY 0.723404 (-3375 3875);
PAINT MONO (-3375 3875);
DISPLAY INVISIBLE (-3375 3875);
FORCEPROP 1 LAST BODY_TYPE PLUMBING
J 0
(-3375 3925);
DISPLAY 0.872340 (-3375 3925);
PAINT GREEN (-3375 3925);
DISPLAY INVISIBLE (-3375 3925);
FORCEPROP 1 LAST HDL_TAP TRUE
J 0
(-3050 3750);
DISPLAY 0.872340 (-3050 3750);
DISPLAY INVISIBLE (-3050 3750);
FORCEPROP 1 LAST PATH I386
J 0
(-3377 3875);
DISPLAY 0.872340 (-3377 3875);
PAINT GREEN (-3377 3875);
DISPLAY INVISIBLE (-3377 3875);
FORCEADD TAP..1
(-3575 4225);
FORCEPROP 3 LASTPIN (-3625 4225) SIG_NAME M_F_CPU0_SA_DQS_DP<3>
J 0
(-3615 4235);
DISPLAY 0.659574 (-3615 4235);
PAINT MONO (-3615 4235);
DISPLAY INVISIBLE (-3615 4235);
FORCEPROP 1 LASTPIN (-3625 4225) BN 3
J 0
(-3637 4233);
DISPLAY 0.489362 (-3637 4233);
PAINT GREEN (-3637 4233);
FORCEPROP 2 LAST CDS_LIB mstr_standard
J 0
(-3575 4225);
DISPLAY 0.723404 (-3575 4225);
PAINT MONO (-3575 4225);
DISPLAY INVISIBLE (-3575 4225);
FORCEPROP 1 LAST BODY_TYPE PLUMBING
J 0
(-3575 4275);
DISPLAY 0.872340 (-3575 4275);
PAINT GREEN (-3575 4275);
DISPLAY INVISIBLE (-3575 4275);
FORCEPROP 1 LAST HDL_TAP TRUE
J 0
(-3250 4100);
DISPLAY 0.872340 (-3250 4100);
DISPLAY INVISIBLE (-3250 4100);
FORCEPROP 1 LAST PATH I387
J 0
(-3577 4225);
DISPLAY 0.872340 (-3577 4225);
PAINT GREEN (-3577 4225);
DISPLAY INVISIBLE (-3577 4225);
FORCEADD TAP..1
(-3575 4325);
FORCEPROP 3 LASTPIN (-3625 4325) SIG_NAME M_F_CPU0_SA_DQS_DP<4>
J 0
(-3615 4335);
DISPLAY 0.659574 (-3615 4335);
PAINT MONO (-3615 4335);
DISPLAY INVISIBLE (-3615 4335);
FORCEPROP 1 LASTPIN (-3625 4325) BN 4
J 0
(-3637 4333);
DISPLAY 0.489362 (-3637 4333);
PAINT GREEN (-3637 4333);
FORCEPROP 2 LAST CDS_LIB mstr_standard
J 0
(-3575 4325);
DISPLAY 0.723404 (-3575 4325);
PAINT MONO (-3575 4325);
DISPLAY INVISIBLE (-3575 4325);
FORCEPROP 1 LAST BODY_TYPE PLUMBING
J 0
(-3575 4375);
DISPLAY 0.872340 (-3575 4375);
PAINT GREEN (-3575 4375);
DISPLAY INVISIBLE (-3575 4375);
FORCEPROP 1 LAST HDL_TAP TRUE
J 0
(-3250 4200);
DISPLAY 0.872340 (-3250 4200);
DISPLAY INVISIBLE (-3250 4200);
FORCEPROP 1 LAST PATH I388
J 0
(-3577 4325);
DISPLAY 0.872340 (-3577 4325);
PAINT GREEN (-3577 4325);
DISPLAY INVISIBLE (-3577 4325);
FORCEADD TAP..1
(-3575 4125);
FORCEPROP 3 LASTPIN (-3625 4125) SIG_NAME M_F_CPU0_SA_DQS_DP<2>
J 0
(-3615 4135);
DISPLAY 0.659574 (-3615 4135);
PAINT MONO (-3615 4135);
DISPLAY INVISIBLE (-3615 4135);
FORCEPROP 1 LASTPIN (-3625 4125) BN 2
J 0
(-3637 4133);
DISPLAY 0.489362 (-3637 4133);
PAINT GREEN (-3637 4133);
FORCEPROP 2 LAST CDS_LIB mstr_standard
J 0
(-3575 4125);
DISPLAY 0.723404 (-3575 4125);
PAINT MONO (-3575 4125);
DISPLAY INVISIBLE (-3575 4125);
FORCEPROP 1 LAST BODY_TYPE PLUMBING
J 0
(-3575 4175);
DISPLAY 0.872340 (-3575 4175);
PAINT GREEN (-3575 4175);
DISPLAY INVISIBLE (-3575 4175);
FORCEPROP 1 LAST HDL_TAP TRUE
J 0
(-3250 4000);
DISPLAY 0.872340 (-3250 4000);
DISPLAY INVISIBLE (-3250 4000);
FORCEPROP 1 LAST PATH I389
J 0
(-3577 4125);
DISPLAY 0.872340 (-3577 4125);
PAINT GREEN (-3577 4125);
DISPLAY INVISIBLE (-3577 4125);
FORCEADD TAP..1
(-3575 4025);
FORCEPROP 3 LASTPIN (-3625 4025) SIG_NAME M_F_CPU0_SA_DQS_DP<1>
J 0
(-3615 4035);
DISPLAY 0.659574 (-3615 4035);
PAINT MONO (-3615 4035);
DISPLAY INVISIBLE (-3615 4035);
FORCEPROP 1 LASTPIN (-3625 4025) BN 1
J 0
(-3637 4033);
DISPLAY 0.489362 (-3637 4033);
PAINT GREEN (-3637 4033);
FORCEPROP 2 LAST CDS_LIB mstr_standard
J 0
(-3575 4025);
DISPLAY 0.723404 (-3575 4025);
PAINT MONO (-3575 4025);
DISPLAY INVISIBLE (-3575 4025);
FORCEPROP 1 LAST BODY_TYPE PLUMBING
J 0
(-3575 4075);
DISPLAY 0.872340 (-3575 4075);
PAINT GREEN (-3575 4075);
DISPLAY INVISIBLE (-3575 4075);
FORCEPROP 1 LAST HDL_TAP TRUE
J 0
(-3250 3900);
DISPLAY 0.872340 (-3250 3900);
DISPLAY INVISIBLE (-3250 3900);
FORCEPROP 1 LAST PATH I390
J 0
(-3577 4025);
DISPLAY 0.872340 (-3577 4025);
PAINT GREEN (-3577 4025);
DISPLAY INVISIBLE (-3577 4025);
FORCEADD TAP..1
(-3575 3925);
FORCEPROP 3 LASTPIN (-3625 3925) SIG_NAME M_F_CPU0_SA_DQS_DP<0>
J 0
(-3615 3935);
DISPLAY 0.659574 (-3615 3935);
PAINT MONO (-3615 3935);
DISPLAY INVISIBLE (-3615 3935);
FORCEPROP 1 LASTPIN (-3625 3925) BN 0
J 0
(-3637 3933);
DISPLAY 0.489362 (-3637 3933);
PAINT GREEN (-3637 3933);
FORCEPROP 2 LAST CDS_LIB mstr_standard
J 0
(-3575 3925);
DISPLAY 0.723404 (-3575 3925);
PAINT MONO (-3575 3925);
DISPLAY INVISIBLE (-3575 3925);
FORCEPROP 1 LAST BODY_TYPE PLUMBING
J 0
(-3575 3975);
DISPLAY 0.872340 (-3575 3975);
PAINT GREEN (-3575 3975);
DISPLAY INVISIBLE (-3575 3975);
FORCEPROP 1 LAST HDL_TAP TRUE
J 0
(-3250 3800);
DISPLAY 0.872340 (-3250 3800);
DISPLAY INVISIBLE (-3250 3800);
FORCEPROP 1 LAST PATH I391
J 0
(-3577 3925);
DISPLAY 0.872340 (-3577 3925);
PAINT GREEN (-3577 3925);
DISPLAY INVISIBLE (-3577 3925);
FORCEADD TAP..1
(-3375 3725);
FORCEPROP 3 LASTPIN (-3425 3725) SIG_NAME M_F_CPU0_SB_DQS_DN<9>
J 0
(-3415 3735);
DISPLAY 0.659574 (-3415 3735);
PAINT MONO (-3415 3735);
DISPLAY INVISIBLE (-3415 3735);
FORCEPROP 1 LASTPIN (-3425 3725) BN 9
J 0
(-3437 3733);
DISPLAY 0.489362 (-3437 3733);
PAINT GREEN (-3437 3733);
FORCEPROP 2 LAST CDS_LIB mstr_standard
J 0
(-3375 3725);
DISPLAY 0.723404 (-3375 3725);
PAINT MONO (-3375 3725);
DISPLAY INVISIBLE (-3375 3725);
FORCEPROP 1 LAST BODY_TYPE PLUMBING
J 0
(-3375 3775);
DISPLAY 0.872340 (-3375 3775);
PAINT GREEN (-3375 3775);
DISPLAY INVISIBLE (-3375 3775);
FORCEPROP 1 LAST HDL_TAP TRUE
J 0
(-3050 3600);
DISPLAY 0.872340 (-3050 3600);
DISPLAY INVISIBLE (-3050 3600);
FORCEPROP 1 LAST PATH I392
J 0
(-3377 3725);
DISPLAY 0.872340 (-3377 3725);
PAINT GREEN (-3377 3725);
DISPLAY INVISIBLE (-3377 3725);
FORCEADD TAP..1
(-3375 3625);
FORCEPROP 3 LASTPIN (-3425 3625) SIG_NAME M_F_CPU0_SB_DQS_DN<8>
J 0
(-3415 3635);
DISPLAY 0.659574 (-3415 3635);
PAINT MONO (-3415 3635);
DISPLAY INVISIBLE (-3415 3635);
FORCEPROP 1 LASTPIN (-3425 3625) BN 8
J 0
(-3437 3633);
DISPLAY 0.489362 (-3437 3633);
PAINT GREEN (-3437 3633);
FORCEPROP 2 LAST CDS_LIB mstr_standard
J 0
(-3375 3625);
DISPLAY 0.723404 (-3375 3625);
PAINT MONO (-3375 3625);
DISPLAY INVISIBLE (-3375 3625);
FORCEPROP 1 LAST BODY_TYPE PLUMBING
J 0
(-3375 3675);
DISPLAY 0.872340 (-3375 3675);
PAINT GREEN (-3375 3675);
DISPLAY INVISIBLE (-3375 3675);
FORCEPROP 1 LAST HDL_TAP TRUE
J 0
(-3050 3500);
DISPLAY 0.872340 (-3050 3500);
DISPLAY INVISIBLE (-3050 3500);
FORCEPROP 1 LAST PATH I393
J 0
(-3377 3625);
DISPLAY 0.872340 (-3377 3625);
PAINT GREEN (-3377 3625);
DISPLAY INVISIBLE (-3377 3625);
FORCEADD TAP..1
(-3375 3525);
FORCEPROP 3 LASTPIN (-3425 3525) SIG_NAME M_F_CPU0_SB_DQS_DN<7>
J 0
(-3415 3535);
DISPLAY 0.659574 (-3415 3535);
PAINT MONO (-3415 3535);
DISPLAY INVISIBLE (-3415 3535);
FORCEPROP 1 LASTPIN (-3425 3525) BN 7
J 0
(-3437 3533);
DISPLAY 0.489362 (-3437 3533);
PAINT GREEN (-3437 3533);
FORCEPROP 2 LAST CDS_LIB mstr_standard
J 0
(-3375 3525);
DISPLAY 0.723404 (-3375 3525);
PAINT MONO (-3375 3525);
DISPLAY INVISIBLE (-3375 3525);
FORCEPROP 1 LAST BODY_TYPE PLUMBING
J 0
(-3375 3575);
DISPLAY 0.872340 (-3375 3575);
PAINT GREEN (-3375 3575);
DISPLAY INVISIBLE (-3375 3575);
FORCEPROP 1 LAST HDL_TAP TRUE
J 0
(-3050 3400);
DISPLAY 0.872340 (-3050 3400);
DISPLAY INVISIBLE (-3050 3400);
FORCEPROP 1 LAST PATH I394
J 0
(-3377 3525);
DISPLAY 0.872340 (-3377 3525);
PAINT GREEN (-3377 3525);
DISPLAY INVISIBLE (-3377 3525);
FORCEADD TAP..1
(-3375 3325);
FORCEPROP 3 LASTPIN (-3425 3325) SIG_NAME M_F_CPU0_SB_DQS_DN<5>
J 0
(-3415 3335);
DISPLAY 0.659574 (-3415 3335);
PAINT MONO (-3415 3335);
DISPLAY INVISIBLE (-3415 3335);
FORCEPROP 1 LASTPIN (-3425 3325) BN 5
J 0
(-3437 3333);
DISPLAY 0.489362 (-3437 3333);
PAINT GREEN (-3437 3333);
FORCEPROP 2 LAST CDS_LIB mstr_standard
J 0
(-3375 3325);
DISPLAY 0.723404 (-3375 3325);
PAINT MONO (-3375 3325);
DISPLAY INVISIBLE (-3375 3325);
FORCEPROP 1 LAST BODY_TYPE PLUMBING
J 0
(-3375 3375);
DISPLAY 0.872340 (-3375 3375);
PAINT GREEN (-3375 3375);
DISPLAY INVISIBLE (-3375 3375);
FORCEPROP 1 LAST HDL_TAP TRUE
J 0
(-3050 3200);
DISPLAY 0.872340 (-3050 3200);
DISPLAY INVISIBLE (-3050 3200);
FORCEPROP 1 LAST PATH I395
J 0
(-3377 3325);
DISPLAY 0.872340 (-3377 3325);
PAINT GREEN (-3377 3325);
DISPLAY INVISIBLE (-3377 3325);
FORCEADD TAP..1
(-3375 3425);
FORCEPROP 3 LASTPIN (-3425 3425) SIG_NAME M_F_CPU0_SB_DQS_DN<6>
J 0
(-3415 3435);
DISPLAY 0.659574 (-3415 3435);
PAINT MONO (-3415 3435);
DISPLAY INVISIBLE (-3415 3435);
FORCEPROP 1 LASTPIN (-3425 3425) BN 6
J 0
(-3437 3433);
DISPLAY 0.489362 (-3437 3433);
PAINT GREEN (-3437 3433);
FORCEPROP 2 LAST CDS_LIB mstr_standard
J 0
(-3375 3425);
DISPLAY 0.723404 (-3375 3425);
PAINT MONO (-3375 3425);
DISPLAY INVISIBLE (-3375 3425);
FORCEPROP 1 LAST BODY_TYPE PLUMBING
J 0
(-3375 3475);
DISPLAY 0.872340 (-3375 3475);
PAINT GREEN (-3375 3475);
DISPLAY INVISIBLE (-3375 3475);
FORCEPROP 1 LAST HDL_TAP TRUE
J 0
(-3050 3300);
DISPLAY 0.872340 (-3050 3300);
DISPLAY INVISIBLE (-3050 3300);
FORCEPROP 1 LAST PATH I396
J 0
(-3377 3425);
DISPLAY 0.872340 (-3377 3425);
PAINT GREEN (-3377 3425);
DISPLAY INVISIBLE (-3377 3425);
FORCEADD TAP..1
(-3575 3675);
FORCEPROP 3 LASTPIN (-3625 3675) SIG_NAME M_F_CPU0_SB_DQS_DP<8>
J 0
(-3615 3685);
DISPLAY 0.659574 (-3615 3685);
PAINT MONO (-3615 3685);
DISPLAY INVISIBLE (-3615 3685);
FORCEPROP 1 LASTPIN (-3625 3675) BN 8
J 0
(-3637 3683);
DISPLAY 0.489362 (-3637 3683);
PAINT GREEN (-3637 3683);
FORCEPROP 2 LAST CDS_LIB mstr_standard
J 0
(-3575 3675);
DISPLAY 0.723404 (-3575 3675);
PAINT MONO (-3575 3675);
DISPLAY INVISIBLE (-3575 3675);
FORCEPROP 1 LAST BODY_TYPE PLUMBING
J 0
(-3575 3725);
DISPLAY 0.872340 (-3575 3725);
PAINT GREEN (-3575 3725);
DISPLAY INVISIBLE (-3575 3725);
FORCEPROP 1 LAST HDL_TAP TRUE
J 0
(-3250 3550);
DISPLAY 0.872340 (-3250 3550);
DISPLAY INVISIBLE (-3250 3550);
FORCEPROP 1 LAST PATH I397
J 0
(-3577 3675);
DISPLAY 0.872340 (-3577 3675);
PAINT GREEN (-3577 3675);
DISPLAY INVISIBLE (-3577 3675);
FORCEADD TAP..1
(-3575 3775);
FORCEPROP 3 LASTPIN (-3625 3775) SIG_NAME M_F_CPU0_SB_DQS_DP<9>
J 0
(-3615 3785);
DISPLAY 0.659574 (-3615 3785);
PAINT MONO (-3615 3785);
DISPLAY INVISIBLE (-3615 3785);
FORCEPROP 1 LASTPIN (-3625 3775) BN 9
J 0
(-3637 3783);
DISPLAY 0.489362 (-3637 3783);
PAINT GREEN (-3637 3783);
FORCEPROP 2 LAST CDS_LIB mstr_standard
J 0
(-3575 3775);
DISPLAY 0.723404 (-3575 3775);
PAINT MONO (-3575 3775);
DISPLAY INVISIBLE (-3575 3775);
FORCEPROP 1 LAST BODY_TYPE PLUMBING
J 0
(-3575 3825);
DISPLAY 0.872340 (-3575 3825);
PAINT GREEN (-3575 3825);
DISPLAY INVISIBLE (-3575 3825);
FORCEPROP 1 LAST HDL_TAP TRUE
J 0
(-3250 3650);
DISPLAY 0.872340 (-3250 3650);
DISPLAY INVISIBLE (-3250 3650);
FORCEPROP 1 LAST PATH I398
J 0
(-3577 3775);
DISPLAY 0.872340 (-3577 3775);
PAINT GREEN (-3577 3775);
DISPLAY INVISIBLE (-3577 3775);
FORCEADD TAP..1
(-3575 3575);
FORCEPROP 3 LASTPIN (-3625 3575) SIG_NAME M_F_CPU0_SB_DQS_DP<7>
J 0
(-3615 3585);
DISPLAY 0.659574 (-3615 3585);
PAINT MONO (-3615 3585);
DISPLAY INVISIBLE (-3615 3585);
FORCEPROP 1 LASTPIN (-3625 3575) BN 7
J 0
(-3637 3583);
DISPLAY 0.489362 (-3637 3583);
PAINT GREEN (-3637 3583);
FORCEPROP 2 LAST CDS_LIB mstr_standard
J 0
(-3575 3575);
DISPLAY 0.723404 (-3575 3575);
PAINT MONO (-3575 3575);
DISPLAY INVISIBLE (-3575 3575);
FORCEPROP 1 LAST BODY_TYPE PLUMBING
J 0
(-3575 3625);
DISPLAY 0.872340 (-3575 3625);
PAINT GREEN (-3575 3625);
DISPLAY INVISIBLE (-3575 3625);
FORCEPROP 1 LAST HDL_TAP TRUE
J 0
(-3250 3450);
DISPLAY 0.872340 (-3250 3450);
DISPLAY INVISIBLE (-3250 3450);
FORCEPROP 1 LAST PATH I399
J 0
(-3577 3575);
DISPLAY 0.872340 (-3577 3575);
PAINT GREEN (-3577 3575);
DISPLAY INVISIBLE (-3577 3575);
FORCEADD TAP..1
(-3575 3475);
FORCEPROP 3 LASTPIN (-3625 3475) SIG_NAME M_F_CPU0_SB_DQS_DP<6>
J 0
(-3615 3485);
DISPLAY 0.659574 (-3615 3485);
PAINT MONO (-3615 3485);
DISPLAY INVISIBLE (-3615 3485);
FORCEPROP 1 LASTPIN (-3625 3475) BN 6
J 0
(-3637 3483);
DISPLAY 0.489362 (-3637 3483);
PAINT GREEN (-3637 3483);
FORCEPROP 2 LAST CDS_LIB mstr_standard
J 0
(-3575 3475);
DISPLAY 0.723404 (-3575 3475);
PAINT MONO (-3575 3475);
DISPLAY INVISIBLE (-3575 3475);
FORCEPROP 1 LAST BODY_TYPE PLUMBING
J 0
(-3575 3525);
DISPLAY 0.872340 (-3575 3525);
PAINT GREEN (-3575 3525);
DISPLAY INVISIBLE (-3575 3525);
FORCEPROP 1 LAST HDL_TAP TRUE
J 0
(-3250 3350);
DISPLAY 0.872340 (-3250 3350);
DISPLAY INVISIBLE (-3250 3350);
FORCEPROP 1 LAST PATH I400
J 0
(-3577 3475);
DISPLAY 0.872340 (-3577 3475);
PAINT GREEN (-3577 3475);
DISPLAY INVISIBLE (-3577 3475);
FORCEADD TAP..1
(-3575 3375);
FORCEPROP 3 LASTPIN (-3625 3375) SIG_NAME M_F_CPU0_SB_DQS_DP<5>
J 0
(-3615 3385);
DISPLAY 0.659574 (-3615 3385);
PAINT MONO (-3615 3385);
DISPLAY INVISIBLE (-3615 3385);
FORCEPROP 1 LASTPIN (-3625 3375) BN 5
J 0
(-3637 3383);
DISPLAY 0.489362 (-3637 3383);
PAINT GREEN (-3637 3383);
FORCEPROP 2 LAST CDS_LIB mstr_standard
J 0
(-3575 3375);
DISPLAY 0.723404 (-3575 3375);
PAINT MONO (-3575 3375);
DISPLAY INVISIBLE (-3575 3375);
FORCEPROP 1 LAST BODY_TYPE PLUMBING
J 0
(-3575 3425);
DISPLAY 0.872340 (-3575 3425);
PAINT GREEN (-3575 3425);
DISPLAY INVISIBLE (-3575 3425);
FORCEPROP 1 LAST HDL_TAP TRUE
J 0
(-3250 3250);
DISPLAY 0.872340 (-3250 3250);
DISPLAY INVISIBLE (-3250 3250);
FORCEPROP 1 LAST PATH I401
J 0
(-3577 3375);
DISPLAY 0.872340 (-3577 3375);
PAINT GREEN (-3577 3375);
DISPLAY INVISIBLE (-3577 3375);
FORCEADD TAP..1
(-3375 3225);
FORCEPROP 3 LASTPIN (-3425 3225) SIG_NAME M_F_CPU0_SB_DQS_DN<4>
J 0
(-3415 3235);
DISPLAY 0.659574 (-3415 3235);
PAINT MONO (-3415 3235);
DISPLAY INVISIBLE (-3415 3235);
FORCEPROP 1 LASTPIN (-3425 3225) BN 4
J 0
(-3437 3233);
DISPLAY 0.489362 (-3437 3233);
PAINT GREEN (-3437 3233);
FORCEPROP 2 LAST CDS_LIB mstr_standard
J 0
(-3375 3225);
DISPLAY 0.723404 (-3375 3225);
PAINT MONO (-3375 3225);
DISPLAY INVISIBLE (-3375 3225);
FORCEPROP 1 LAST BODY_TYPE PLUMBING
J 0
(-3375 3275);
DISPLAY 0.872340 (-3375 3275);
PAINT GREEN (-3375 3275);
DISPLAY INVISIBLE (-3375 3275);
FORCEPROP 1 LAST HDL_TAP TRUE
J 0
(-3050 3100);
DISPLAY 0.872340 (-3050 3100);
DISPLAY INVISIBLE (-3050 3100);
FORCEPROP 1 LAST PATH I402
J 0
(-3377 3225);
DISPLAY 0.872340 (-3377 3225);
PAINT GREEN (-3377 3225);
DISPLAY INVISIBLE (-3377 3225);
FORCEADD TAP..1
(-3375 3125);
FORCEPROP 3 LASTPIN (-3425 3125) SIG_NAME M_F_CPU0_SB_DQS_DN<3>
J 0
(-3415 3135);
DISPLAY 0.659574 (-3415 3135);
PAINT MONO (-3415 3135);
DISPLAY INVISIBLE (-3415 3135);
FORCEPROP 1 LASTPIN (-3425 3125) BN 3
J 0
(-3437 3133);
DISPLAY 0.489362 (-3437 3133);
PAINT GREEN (-3437 3133);
FORCEPROP 2 LAST CDS_LIB mstr_standard
J 0
(-3375 3125);
DISPLAY 0.723404 (-3375 3125);
PAINT MONO (-3375 3125);
DISPLAY INVISIBLE (-3375 3125);
FORCEPROP 1 LAST BODY_TYPE PLUMBING
J 0
(-3375 3175);
DISPLAY 0.872340 (-3375 3175);
PAINT GREEN (-3375 3175);
DISPLAY INVISIBLE (-3375 3175);
FORCEPROP 1 LAST HDL_TAP TRUE
J 0
(-3050 3000);
DISPLAY 0.872340 (-3050 3000);
DISPLAY INVISIBLE (-3050 3000);
FORCEPROP 1 LAST PATH I403
J 0
(-3377 3125);
DISPLAY 0.872340 (-3377 3125);
PAINT GREEN (-3377 3125);
DISPLAY INVISIBLE (-3377 3125);
FORCEADD TAP..1
(-3375 3025);
FORCEPROP 3 LASTPIN (-3425 3025) SIG_NAME M_F_CPU0_SB_DQS_DN<2>
J 0
(-3415 3035);
DISPLAY 0.659574 (-3415 3035);
PAINT MONO (-3415 3035);
DISPLAY INVISIBLE (-3415 3035);
FORCEPROP 1 LASTPIN (-3425 3025) BN 2
J 0
(-3437 3033);
DISPLAY 0.489362 (-3437 3033);
PAINT GREEN (-3437 3033);
FORCEPROP 2 LAST CDS_LIB mstr_standard
J 0
(-3375 3025);
DISPLAY 0.723404 (-3375 3025);
PAINT MONO (-3375 3025);
DISPLAY INVISIBLE (-3375 3025);
FORCEPROP 1 LAST BODY_TYPE PLUMBING
J 0
(-3375 3075);
DISPLAY 0.872340 (-3375 3075);
PAINT GREEN (-3375 3075);
DISPLAY INVISIBLE (-3375 3075);
FORCEPROP 1 LAST HDL_TAP TRUE
J 0
(-3050 2900);
DISPLAY 0.872340 (-3050 2900);
DISPLAY INVISIBLE (-3050 2900);
FORCEPROP 1 LAST PATH I404
J 0
(-3377 3025);
DISPLAY 0.872340 (-3377 3025);
PAINT GREEN (-3377 3025);
DISPLAY INVISIBLE (-3377 3025);
FORCEADD TAP..1
(-3375 2825);
FORCEPROP 3 LASTPIN (-3425 2825) SIG_NAME M_F_CPU0_SB_DQS_DN<0>
J 0
(-3415 2835);
DISPLAY 0.659574 (-3415 2835);
PAINT MONO (-3415 2835);
DISPLAY INVISIBLE (-3415 2835);
FORCEPROP 1 LASTPIN (-3425 2825) BN 0
J 0
(-3437 2833);
DISPLAY 0.489362 (-3437 2833);
PAINT GREEN (-3437 2833);
FORCEPROP 2 LAST CDS_LIB mstr_standard
J 0
(-3375 2825);
DISPLAY 0.723404 (-3375 2825);
PAINT MONO (-3375 2825);
DISPLAY INVISIBLE (-3375 2825);
FORCEPROP 1 LAST BODY_TYPE PLUMBING
J 0
(-3375 2875);
DISPLAY 0.872340 (-3375 2875);
PAINT GREEN (-3375 2875);
DISPLAY INVISIBLE (-3375 2875);
FORCEPROP 1 LAST HDL_TAP TRUE
J 0
(-3050 2700);
DISPLAY 0.872340 (-3050 2700);
DISPLAY INVISIBLE (-3050 2700);
FORCEPROP 1 LAST PATH I405
J 0
(-3377 2825);
DISPLAY 0.872340 (-3377 2825);
PAINT GREEN (-3377 2825);
DISPLAY INVISIBLE (-3377 2825);
FORCEADD TAP..1
(-3375 2925);
FORCEPROP 3 LASTPIN (-3425 2925) SIG_NAME M_F_CPU0_SB_DQS_DN<1>
J 0
(-3415 2935);
DISPLAY 0.659574 (-3415 2935);
PAINT MONO (-3415 2935);
DISPLAY INVISIBLE (-3415 2935);
FORCEPROP 1 LASTPIN (-3425 2925) BN 1
J 0
(-3437 2933);
DISPLAY 0.489362 (-3437 2933);
PAINT GREEN (-3437 2933);
FORCEPROP 2 LAST CDS_LIB mstr_standard
J 0
(-3375 2925);
DISPLAY 0.723404 (-3375 2925);
PAINT MONO (-3375 2925);
DISPLAY INVISIBLE (-3375 2925);
FORCEPROP 1 LAST BODY_TYPE PLUMBING
J 0
(-3375 2975);
DISPLAY 0.872340 (-3375 2975);
PAINT GREEN (-3375 2975);
DISPLAY INVISIBLE (-3375 2975);
FORCEPROP 1 LAST HDL_TAP TRUE
J 0
(-3050 2800);
DISPLAY 0.872340 (-3050 2800);
DISPLAY INVISIBLE (-3050 2800);
FORCEPROP 1 LAST PATH I406
J 0
(-3377 2925);
DISPLAY 0.872340 (-3377 2925);
PAINT GREEN (-3377 2925);
DISPLAY INVISIBLE (-3377 2925);
FORCEADD TAP..1
(-3575 3175);
FORCEPROP 3 LASTPIN (-3625 3175) SIG_NAME M_F_CPU0_SB_DQS_DP<3>
J 0
(-3615 3185);
DISPLAY 0.659574 (-3615 3185);
PAINT MONO (-3615 3185);
DISPLAY INVISIBLE (-3615 3185);
FORCEPROP 1 LASTPIN (-3625 3175) BN 3
J 0
(-3637 3183);
DISPLAY 0.489362 (-3637 3183);
PAINT GREEN (-3637 3183);
FORCEPROP 2 LAST CDS_LIB mstr_standard
J 0
(-3575 3175);
DISPLAY 0.723404 (-3575 3175);
PAINT MONO (-3575 3175);
DISPLAY INVISIBLE (-3575 3175);
FORCEPROP 1 LAST BODY_TYPE PLUMBING
J 0
(-3575 3225);
DISPLAY 0.872340 (-3575 3225);
PAINT GREEN (-3575 3225);
DISPLAY INVISIBLE (-3575 3225);
FORCEPROP 1 LAST HDL_TAP TRUE
J 0
(-3250 3050);
DISPLAY 0.872340 (-3250 3050);
DISPLAY INVISIBLE (-3250 3050);
FORCEPROP 1 LAST PATH I407
J 0
(-3577 3175);
DISPLAY 0.872340 (-3577 3175);
PAINT GREEN (-3577 3175);
DISPLAY INVISIBLE (-3577 3175);
FORCEADD TAP..1
(-3575 3275);
FORCEPROP 3 LASTPIN (-3625 3275) SIG_NAME M_F_CPU0_SB_DQS_DP<4>
J 0
(-3615 3285);
DISPLAY 0.659574 (-3615 3285);
PAINT MONO (-3615 3285);
DISPLAY INVISIBLE (-3615 3285);
FORCEPROP 1 LASTPIN (-3625 3275) BN 4
J 0
(-3637 3283);
DISPLAY 0.489362 (-3637 3283);
PAINT GREEN (-3637 3283);
FORCEPROP 2 LAST CDS_LIB mstr_standard
J 0
(-3575 3275);
DISPLAY 0.723404 (-3575 3275);
PAINT MONO (-3575 3275);
DISPLAY INVISIBLE (-3575 3275);
FORCEPROP 1 LAST BODY_TYPE PLUMBING
J 0
(-3575 3325);
DISPLAY 0.872340 (-3575 3325);
PAINT GREEN (-3575 3325);
DISPLAY INVISIBLE (-3575 3325);
FORCEPROP 1 LAST HDL_TAP TRUE
J 0
(-3250 3150);
DISPLAY 0.872340 (-3250 3150);
DISPLAY INVISIBLE (-3250 3150);
FORCEPROP 1 LAST PATH I408
J 0
(-3577 3275);
DISPLAY 0.872340 (-3577 3275);
PAINT GREEN (-3577 3275);
DISPLAY INVISIBLE (-3577 3275);
FORCEADD TAP..1
(-3575 3075);
FORCEPROP 3 LASTPIN (-3625 3075) SIG_NAME M_F_CPU0_SB_DQS_DP<2>
J 0
(-3615 3085);
DISPLAY 0.659574 (-3615 3085);
PAINT MONO (-3615 3085);
DISPLAY INVISIBLE (-3615 3085);
FORCEPROP 1 LASTPIN (-3625 3075) BN 2
J 0
(-3637 3083);
DISPLAY 0.489362 (-3637 3083);
PAINT GREEN (-3637 3083);
FORCEPROP 2 LAST CDS_LIB mstr_standard
J 0
(-3575 3075);
DISPLAY 0.723404 (-3575 3075);
PAINT MONO (-3575 3075);
DISPLAY INVISIBLE (-3575 3075);
FORCEPROP 1 LAST BODY_TYPE PLUMBING
J 0
(-3575 3125);
DISPLAY 0.872340 (-3575 3125);
PAINT GREEN (-3575 3125);
DISPLAY INVISIBLE (-3575 3125);
FORCEPROP 1 LAST HDL_TAP TRUE
J 0
(-3250 2950);
DISPLAY 0.872340 (-3250 2950);
DISPLAY INVISIBLE (-3250 2950);
FORCEPROP 1 LAST PATH I409
J 0
(-3577 3075);
DISPLAY 0.872340 (-3577 3075);
PAINT GREEN (-3577 3075);
DISPLAY INVISIBLE (-3577 3075);
FORCEADD TAP..1
(-3575 2975);
FORCEPROP 3 LASTPIN (-3625 2975) SIG_NAME M_F_CPU0_SB_DQS_DP<1>
J 0
(-3615 2985);
DISPLAY 0.659574 (-3615 2985);
PAINT MONO (-3615 2985);
DISPLAY INVISIBLE (-3615 2985);
FORCEPROP 1 LASTPIN (-3625 2975) BN 1
J 0
(-3637 2983);
DISPLAY 0.489362 (-3637 2983);
PAINT GREEN (-3637 2983);
FORCEPROP 2 LAST CDS_LIB mstr_standard
J 0
(-3575 2975);
DISPLAY 0.723404 (-3575 2975);
PAINT MONO (-3575 2975);
DISPLAY INVISIBLE (-3575 2975);
FORCEPROP 1 LAST BODY_TYPE PLUMBING
J 0
(-3575 3025);
DISPLAY 0.872340 (-3575 3025);
PAINT GREEN (-3575 3025);
DISPLAY INVISIBLE (-3575 3025);
FORCEPROP 1 LAST HDL_TAP TRUE
J 0
(-3250 2850);
DISPLAY 0.872340 (-3250 2850);
DISPLAY INVISIBLE (-3250 2850);
FORCEPROP 1 LAST PATH I410
J 0
(-3577 2975);
DISPLAY 0.872340 (-3577 2975);
PAINT GREEN (-3577 2975);
DISPLAY INVISIBLE (-3577 2975);
FORCEADD TAP..1
(-3575 2875);
FORCEPROP 3 LASTPIN (-3625 2875) SIG_NAME M_F_CPU0_SB_DQS_DP<0>
J 0
(-3615 2885);
DISPLAY 0.659574 (-3615 2885);
PAINT MONO (-3615 2885);
DISPLAY INVISIBLE (-3615 2885);
FORCEPROP 1 LASTPIN (-3625 2875) BN 0
J 0
(-3637 2883);
DISPLAY 0.489362 (-3637 2883);
PAINT GREEN (-3637 2883);
FORCEPROP 2 LAST CDS_LIB mstr_standard
J 0
(-3575 2875);
DISPLAY 0.723404 (-3575 2875);
PAINT MONO (-3575 2875);
DISPLAY INVISIBLE (-3575 2875);
FORCEPROP 1 LAST BODY_TYPE PLUMBING
J 0
(-3575 2925);
DISPLAY 0.872340 (-3575 2925);
PAINT GREEN (-3575 2925);
DISPLAY INVISIBLE (-3575 2925);
FORCEPROP 1 LAST HDL_TAP TRUE
J 0
(-3250 2750);
DISPLAY 0.872340 (-3250 2750);
DISPLAY INVISIBLE (-3250 2750);
FORCEPROP 1 LAST PATH I411
J 0
(-3577 2875);
DISPLAY 0.872340 (-3577 2875);
PAINT GREEN (-3577 2875);
DISPLAY INVISIBLE (-3577 2875);
FORCEADD SCONN288_DDR506112002KQ..2
(-4525 3825);
FORCEPROP 1 LAST LOCATION J23
J 0
(-5125 5150);
DISPLAY 0.468085 (-5125 5150);
PAINT SKYBLUE (-5125 5150);
FORCEPROP 0 LAST $SEC 2
J 0
(-4975 5300);
DISPLAY 0.680851 (-4975 5300);
PAINT MONO (-4975 5300);
DISPLAY INVISIBLE (-4975 5300);
FORCEPROP 0 LAST CDS_SEC 2
J 0
(-4975 5300);
DISPLAY 1.021277 (-4975 5300);
DISPLAY INVISIBLE (-4975 5300);
FORCEPROP 0 LASTPIN (-3775 3875) $PN 12
J 0
(-3765 3885);
DISPLAY 0.680851 (-3765 3885);
PAINT MONO (-3765 3885);
FORCEPROP 0 LASTPIN (-3775 3925) $PN 11
J 0
(-3765 3935);
DISPLAY 0.680851 (-3765 3935);
PAINT MONO (-3765 3935);
FORCEPROP 0 LASTPIN (-3775 2825) $PN 105
J 0
(-3765 2835);
DISPLAY 0.680851 (-3765 2835);
PAINT MONO (-3765 2835);
FORCEPROP 0 LASTPIN (-3775 2875) $PN 104
J 0
(-3765 2885);
DISPLAY 0.680851 (-3765 2885);
PAINT MONO (-3765 2885);
FORCEPROP 0 LASTPIN (-3775 3975) $PN 23
J 0
(-3765 3985);
DISPLAY 0.680851 (-3765 3985);
PAINT MONO (-3765 3985);
FORCEPROP 0 LASTPIN (-3775 4025) $PN 22
J 0
(-3765 4035);
DISPLAY 0.680851 (-3765 4035);
PAINT MONO (-3765 4035);
FORCEPROP 0 LASTPIN (-3775 2925) $PN 116
J 0
(-3765 2935);
DISPLAY 0.680851 (-3765 2935);
PAINT MONO (-3765 2935);
FORCEPROP 0 LASTPIN (-3775 2975) $PN 115
J 0
(-3765 2985);
DISPLAY 0.680851 (-3765 2985);
PAINT MONO (-3765 2985);
FORCEPROP 0 LASTPIN (-3775 4075) $PN 34
J 0
(-3765 4085);
DISPLAY 0.680851 (-3765 4085);
PAINT MONO (-3765 4085);
FORCEPROP 0 LASTPIN (-3775 4125) $PN 33
J 0
(-3765 4135);
DISPLAY 0.680851 (-3765 4135);
PAINT MONO (-3765 4135);
FORCEPROP 0 LASTPIN (-3775 3025) $PN 127
J 0
(-3765 3035);
DISPLAY 0.680851 (-3765 3035);
PAINT MONO (-3765 3035);
FORCEPROP 0 LASTPIN (-3775 3075) $PN 126
J 0
(-3765 3085);
DISPLAY 0.680851 (-3765 3085);
PAINT MONO (-3765 3085);
FORCEPROP 0 LASTPIN (-3775 4175) $PN 45
J 0
(-3765 4185);
DISPLAY 0.680851 (-3765 4185);
PAINT MONO (-3765 4185);
FORCEPROP 0 LASTPIN (-3775 4225) $PN 44
J 0
(-3765 4235);
DISPLAY 0.680851 (-3765 4235);
PAINT MONO (-3765 4235);
FORCEPROP 0 LASTPIN (-3775 3125) $PN 138
J 0
(-3765 3135);
DISPLAY 0.680851 (-3765 3135);
PAINT MONO (-3765 3135);
FORCEPROP 0 LASTPIN (-3775 3175) $PN 137
J 0
(-3765 3185);
DISPLAY 0.680851 (-3765 3185);
PAINT MONO (-3765 3185);
FORCEPROP 0 LASTPIN (-3775 4275) $PN 56
J 0
(-3765 4285);
DISPLAY 0.680851 (-3765 4285);
PAINT MONO (-3765 4285);
FORCEPROP 0 LASTPIN (-3775 4325) $PN 55
J 0
(-3765 4335);
DISPLAY 0.680851 (-3765 4335);
PAINT MONO (-3765 4335);
FORCEPROP 0 LASTPIN (-3775 3225) $PN 238
J 0
(-3765 3235);
DISPLAY 0.680851 (-3765 3235);
PAINT MONO (-3765 3235);
FORCEPROP 0 LASTPIN (-3775 3275) $PN 239
J 0
(-3765 3285);
DISPLAY 0.680851 (-3765 3285);
PAINT MONO (-3765 3285);
FORCEPROP 0 LASTPIN (-3775 4375) $PN 156
J 0
(-3765 4385);
DISPLAY 0.680851 (-3765 4385);
PAINT MONO (-3765 4385);
FORCEPROP 0 LASTPIN (-3775 4425) $PN 157
J 0
(-3765 4435);
DISPLAY 0.680851 (-3765 4435);
PAINT MONO (-3765 4435);
FORCEPROP 0 LASTPIN (-3775 3325) $PN 249
J 0
(-3765 3335);
DISPLAY 0.680851 (-3765 3335);
PAINT MONO (-3765 3335);
FORCEPROP 0 LASTPIN (-3775 3375) $PN 250
J 0
(-3765 3385);
DISPLAY 0.680851 (-3765 3385);
PAINT MONO (-3765 3385);
FORCEPROP 0 LASTPIN (-3775 4475) $PN 167
J 0
(-3765 4485);
DISPLAY 0.680851 (-3765 4485);
PAINT MONO (-3765 4485);
FORCEPROP 0 LASTPIN (-3775 4525) $PN 168
J 0
(-3765 4535);
DISPLAY 0.680851 (-3765 4535);
PAINT MONO (-3765 4535);
FORCEPROP 0 LASTPIN (-3775 3425) $PN 260
J 0
(-3765 3435);
DISPLAY 0.680851 (-3765 3435);
PAINT MONO (-3765 3435);
FORCEPROP 0 LASTPIN (-3775 3475) $PN 261
J 0
(-3765 3485);
DISPLAY 0.680851 (-3765 3485);
PAINT MONO (-3765 3485);
FORCEPROP 0 LASTPIN (-3775 4575) $PN 178
J 0
(-3765 4585);
DISPLAY 0.680851 (-3765 4585);
PAINT MONO (-3765 4585);
FORCEPROP 0 LASTPIN (-3775 4625) $PN 179
J 0
(-3765 4635);
DISPLAY 0.680851 (-3765 4635);
PAINT MONO (-3765 4635);
FORCEPROP 0 LASTPIN (-3775 3525) $PN 271
J 0
(-3765 3535);
DISPLAY 0.680851 (-3765 3535);
PAINT MONO (-3765 3535);
FORCEPROP 0 LASTPIN (-3775 3575) $PN 272
J 0
(-3765 3585);
DISPLAY 0.680851 (-3765 3585);
PAINT MONO (-3765 3585);
FORCEPROP 0 LASTPIN (-3775 4675) $PN 189
J 0
(-3765 4685);
DISPLAY 0.680851 (-3765 4685);
PAINT MONO (-3765 4685);
FORCEPROP 0 LASTPIN (-3775 4725) $PN 190
J 0
(-3765 4735);
DISPLAY 0.680851 (-3765 4735);
PAINT MONO (-3765 4735);
FORCEPROP 0 LASTPIN (-3775 3625) $PN 282
J 0
(-3765 3635);
DISPLAY 0.680851 (-3765 3635);
PAINT MONO (-3765 3635);
FORCEPROP 0 LASTPIN (-3775 3675) $PN 283
J 0
(-3765 3685);
DISPLAY 0.680851 (-3765 3685);
PAINT MONO (-3765 3685);
FORCEPROP 0 LASTPIN (-3775 4775) $PN 200
J 0
(-3765 4785);
DISPLAY 0.680851 (-3765 4785);
PAINT MONO (-3765 4785);
FORCEPROP 0 LASTPIN (-3775 4825) $PN 201
J 0
(-3765 4835);
DISPLAY 0.680851 (-3765 4835);
PAINT MONO (-3765 4835);
FORCEPROP 0 LASTPIN (-3775 3725) $PN 94
J 0
(-3765 3735);
DISPLAY 0.680851 (-3765 3735);
PAINT MONO (-3765 3735);
FORCEPROP 0 LASTPIN (-3775 3775) $PN 93
J 0
(-3765 3785);
DISPLAY 0.680851 (-3765 3785);
PAINT MONO (-3765 3785);
FORCEPROP 2 LAST PART_TYPE SMLF
J 0
(-4975 5250);
DISPLAY 1.021277 (-4975 5250);
FORCEPROP 1 LAST MATERIAL IO
J 0
(-5125 5000);
DISPLAY 0.468085 (-5125 5000);
PAINT SKYBLUE (-5125 5000);
FORCEPROP 2 LAST VALUE SCONN288_DDR506112002KQ
J 0
(-4975 5200);
DISPLAY 0.489362 (-4975 5200);
PAINT SKYBLUE (-4975 5200);
FORCEPROP 1 LAST PART_NUMBER DFHST8FS479
J 0
(-5125 5075);
DISPLAY 0.468085 (-5125 5075);
PAINT SKYBLUE (-5125 5075);
FORCEPROP 1 LAST CDS_LMAN_SYM_OUTLINE -600,1150,600,-1150
J 0
(-4525 3825);
DISPLAY 0.468085 (-4525 3825);
PAINT GREEN (-4525 3825);
DISPLAY INVISIBLE (-4525 3825);
FORCEPROP 1 LAST PATH I412
J 0
(-4525 3825);
DISPLAY 0.723404 (-4525 3825);
PAINT GREEN (-4525 3825);
DISPLAY INVISIBLE (-4525 3825);
FORCEPROP 1 LAST NEEDS_NO_SIZE TRUE
J 0
(-4525 3825);
DISPLAY 0.723404 (-4525 3825);
PAINT GREEN (-4525 3825);
DISPLAY INVISIBLE (-4525 3825);
FORCEPROP 2 LAST CDS_LIB pure_quanta
J 0
(-4525 3825);
DISPLAY INVISIBLE (-4525 3825);
FORCEADD GND..1
(-2925 5800);
FORCEPROP 3 LASTPIN (-2925 5850) SIG_NAME GND\g
J 0
(-2915 5860);
DISPLAY 0.659574 (-2915 5860);
PAINT MONO (-2915 5860);
DISPLAY INVISIBLE (-2915 5860);
FORCEPROP 1 LAST SIZE 1B
J 0
(-2850 5750);
DISPLAY 0.723404 (-2850 5750);
PAINT GREEN (-2850 5750);
DISPLAY INVISIBLE (-2850 5750);
FORCEPROP 2 LAST BOM_COST MEM
J 0
(-2900 5925);
DISPLAY 0.659574 (-2900 5925);
DISPLAY INVISIBLE (-2900 5925);
FORCEPROP 2 LAST CDS_LIB pure_quanta_power
J 0
(-2925 5800);
DISPLAY INVISIBLE (-2925 5800);
FORCEPROP 1 LAST PATH I413
J 0
(-2850 5800);
DISPLAY 0.872340 (-2850 5800);
PAINT AQUA (-2850 5800);
DISPLAY INVISIBLE (-2850 5800);
FORCEPROP 2 LAST ROOM MEM_EFGH_DECOUPLING_CAPS
J 0
(-2900 5875);
DISPLAY 0.659574 (-2900 5875);
PAINT RED (-2900 5875);
DISPLAY INVISIBLE (-2900 5875);
FORCEPROP 1 LAST HDL_POWER GND
J 0
(-2925 5950);
DISPLAY 0.723404 (-2925 5950);
PAINT GREEN (-2925 5950);
DISPLAY INVISIBLE (-2925 5950);
FORCEADD Q_CAP..1
R 2
(-2925 6150);
FORCEPROP 1 LAST LOCATION C154
J 2
(-2975 6250);
DISPLAY 0.489362 (-2975 6250);
PAINT SKYBLUE (-2975 6250);
FORCEPROP 0 LAST $SEC 1
J 0
(-2975 6300);
DISPLAY 0.680851 (-2975 6300);
PAINT MONO (-2975 6300);
DISPLAY INVISIBLE (-2975 6300);
FORCEPROP 0 LAST CDS_SEC 1
J 0
(-2975 6300);
DISPLAY 0.680851 (-2975 6300);
DISPLAY INVISIBLE (-2975 6300);
FORCEPROP 1 LASTPIN (-2925 6250) $PN 1
J 2
(-2935 6230);
DISPLAY 0.489362 (-2935 6230);
PAINT MONO (-2935 6230);
FORCEPROP 1 LASTPIN (-2925 6050) $PN 2
J 2
(-2935 6030);
DISPLAY 0.489362 (-2935 6030);
PAINT MONO (-2935 6030);
FORCEPROP 1 LAST MATERIAL X6S
J 2
(-2975 6050);
DISPLAY 0.489362 (-2975 6050);
PAINT SKYBLUE (-2975 6050);
FORCEPROP 1 LAST TOLERANCE 10%
J 2
(-2975 6100);
DISPLAY 0.489362 (-2975 6100);
PAINT SKYBLUE (-2975 6100);
FORCEPROP 1 LAST VALUE 10UF
J 2
(-2975 6200);
DISPLAY 0.489362 (-2975 6200);
PAINT SKYBLUE (-2975 6200);
FORCEPROP 1 LAST PART_NUMBER CH6104KEA00
J 2
(-2975 6000);
DISPLAY 0.489362 (-2975 6000);
PAINT SKYBLUE (-2975 6000);
FORCEPROP 1 LAST VOLTAGE 25V
J 2
(-2975 6150);
DISPLAY 0.489362 (-2975 6150);
PAINT SKYBLUE (-2975 6150);
FORCEPROP 1 LAST PACK_TYPE C0805
J 2
(-2975 5950);
DISPLAY 0.489362 (-2975 5950);
PAINT SKYBLUE (-2975 5950);
FORCEPROP 2 LAST CDS_LIB pure_quanta
J 0
(-2925 6150);
DISPLAY INVISIBLE (-2925 6150);
FORCEPROP 0 LAST BOM_COST MEM
J 2
(-2980 6295);
DISPLAY 0.595745 (-2980 6295);
PAINT MONO (-2980 6295);
DISPLAY INVISIBLE (-2980 6295);
FORCEPROP 1 LAST PATH I414
J 2
(-2975 6300);
DISPLAY 0.978723 (-2975 6300);
PAINT WHITE (-2975 6300);
DISPLAY INVISIBLE (-2975 6300);
FORCEPROP 0 LAST ROOM MEM_CH_A_CPU0_DIMM1
J 2
(-2980 6295);
DISPLAY 0.595745 (-2980 6295);
PAINT RED (-2980 6295);
DISPLAY INVISIBLE (-2980 6295);
FORCEADD Q_CAP..1
R 2
(-2350 6150);
FORCEPROP 1 LAST LOCATION C155
J 2
(-2400 6250);
DISPLAY 0.489362 (-2400 6250);
PAINT SKYBLUE (-2400 6250);
FORCEPROP 0 LAST $SEC 1
J 0
(-2400 6300);
DISPLAY 0.680851 (-2400 6300);
PAINT MONO (-2400 6300);
DISPLAY INVISIBLE (-2400 6300);
FORCEPROP 0 LAST CDS_SEC 1
J 0
(-2400 6300);
DISPLAY 0.680851 (-2400 6300);
DISPLAY INVISIBLE (-2400 6300);
FORCEPROP 1 LASTPIN (-2350 6250) $PN 1
J 2
(-2360 6230);
DISPLAY 0.489362 (-2360 6230);
PAINT MONO (-2360 6230);
FORCEPROP 1 LASTPIN (-2350 6050) $PN 2
J 2
(-2360 6030);
DISPLAY 0.489362 (-2360 6030);
PAINT MONO (-2360 6030);
FORCEPROP 1 LAST MATERIAL X6S
J 2
(-2400 6050);
DISPLAY 0.489362 (-2400 6050);
PAINT SKYBLUE (-2400 6050);
FORCEPROP 1 LAST TOLERANCE 10%
J 2
(-2400 6100);
DISPLAY 0.489362 (-2400 6100);
PAINT SKYBLUE (-2400 6100);
FORCEPROP 1 LAST VALUE 10UF
J 2
(-2400 6200);
DISPLAY 0.489362 (-2400 6200);
PAINT SKYBLUE (-2400 6200);
FORCEPROP 1 LAST PART_NUMBER CH6104KEA00
J 2
(-2400 6000);
DISPLAY 0.489362 (-2400 6000);
PAINT SKYBLUE (-2400 6000);
FORCEPROP 1 LAST VOLTAGE 25V
J 2
(-2400 6150);
DISPLAY 0.489362 (-2400 6150);
PAINT SKYBLUE (-2400 6150);
FORCEPROP 1 LAST PACK_TYPE C0805
J 2
(-2400 5950);
DISPLAY 0.489362 (-2400 5950);
PAINT SKYBLUE (-2400 5950);
FORCEPROP 2 LAST CDS_LIB pure_quanta
J 0
(-2350 6150);
DISPLAY INVISIBLE (-2350 6150);
FORCEPROP 0 LAST BOM_COST MEM
J 2
(-2405 6295);
DISPLAY 0.595745 (-2405 6295);
PAINT MONO (-2405 6295);
DISPLAY INVISIBLE (-2405 6295);
FORCEPROP 1 LAST PATH I415
J 2
(-2400 6300);
DISPLAY 0.978723 (-2400 6300);
PAINT WHITE (-2400 6300);
DISPLAY INVISIBLE (-2400 6300);
FORCEPROP 0 LAST ROOM MEM_CH_A_CPU0_DIMM1
J 2
(-2405 6295);
DISPLAY 0.595745 (-2405 6295);
PAINT RED (-2405 6295);
DISPLAY INVISIBLE (-2405 6295);
FORCEADD UNIVERSAL_POWER..1
(-2925 6475);
FORCEPROP 3 LASTPIN (-2925 6425) SIG_NAME P12V_MEM_1\g
J 0
(-2915 6435);
DISPLAY 0.659574 (-2915 6435);
PAINT MONO (-2915 6435);
DISPLAY INVISIBLE (-2915 6435);
FORCEPROP 1 LAST HDL_POWER P12V_MEM_1
J 1
(-2950 6525);
DISPLAY 0.489362 (-2950 6525);
PAINT GREEN (-2950 6525);
FORCEPROP 2 LAST BOM_COST VR_SYSTEM
J 0
(-2925 6575);
DISPLAY 0.617021 (-2925 6575);
PAINT PURPLE (-2925 6575);
DISPLAY INVISIBLE (-2925 6575);
FORCEPROP 2 LAST CDS_LIB pure_quanta_power
J 0
(-2925 6475);
DISPLAY INVISIBLE (-2925 6475);
FORCEPROP 1 LAST PATH I416
J 0
(-2875 6500);
DISPLAY 0.872340 (-2875 6500);
PAINT AQUA (-2875 6500);
DISPLAY INVISIBLE (-2875 6500);
FORCEADD OFFPAGE..1
(-8375 3025);
FORCEPROP 2 LAST $XR5 89 
J 0
(-9107 3025);
DISPLAY 0.638298 (-9107 3025);
PAINT MONO (-9107 3025);
FORCEPROP 2 LAST $XR4 88 
J 0
(-9017 3025);
DISPLAY 0.638298 (-9017 3025);
PAINT MONO (-9017 3025);
FORCEPROP 2 LAST $XR3 87 
J 0
(-8927 3025);
DISPLAY 0.638298 (-8927 3025);
PAINT MONO (-8927 3025);
FORCEPROP 2 LAST $XR2 86 
J 0
(-8837 3025);
DISPLAY 0.638298 (-8837 3025);
PAINT MONO (-8837 3025);
FORCEPROP 2 LAST $XR1 85 
J 0
(-8747 3025);
DISPLAY 0.638298 (-8747 3025);
PAINT MONO (-8747 3025);
FORCEPROP 2 LAST $XR0 136 
J 0
(-8657 3025);
DISPLAY 0.638298 (-8657 3025);
PAINT MONO (-8657 3025);
FORCEPROP 2 LAST PATH I417
J 0
(-8650 3075);
DISPLAY 0.680851 (-8650 3075);
DISPLAY INVISIBLE (-8650 3075);
FORCEPROP 2 LAST CDS_LIB mstr_standard
J 0
(-8375 3025);
DISPLAY 0.808511 (-8375 3025);
DISPLAY INVISIBLE (-8375 3025);
FORCEPROP 1 LAST OFFPAGE TRUE
J 0
(-8050 2900);
DISPLAY 0.872340 (-8050 2900);
PAINT GREEN (-8050 2900);
DISPLAY INVISIBLE (-8050 2900);
FORCEPROP 1 LAST COMMENT_BODY TRUE
J 0
(-8250 2925);
DISPLAY 0.872340 (-8250 2925);
PAINT GREEN (-8250 2925);
DISPLAY INVISIBLE (-8250 2925);
FORCEADD Q_RES..1
(-7825 3025);
FORCEPROP 1 LAST $LOCATION R1573
J 0
(-7875 3050);
DISPLAY 0.510638 (-7875 3050);
PAINT SKYBLUE (-7875 3050);
FORCEPROP 0 LAST CDS_LOCATION R1573
J 0
(-7875 3125);
DISPLAY 0.680851 (-7875 3125);
DISPLAY INVISIBLE (-7875 3125);
FORCEPROP 0 LAST $SEC 1
J 0
(-7875 3125);
DISPLAY 0.680851 (-7875 3125);
PAINT MONO (-7875 3125);
DISPLAY INVISIBLE (-7875 3125);
FORCEPROP 0 LAST CDS_SEC 1
J 0
(-7875 3125);
DISPLAY 0.680851 (-7875 3125);
DISPLAY INVISIBLE (-7875 3125);
FORCEPROP 1 LASTPIN (-7925 3025) $PN 1
J 0
(-7913 3037);
DISPLAY 0.787234 (-7913 3037);
PAINT MONO (-7913 3037);
FORCEPROP 1 LASTPIN (-7725 3025) $PN 2
J 0
(-7763 3037);
DISPLAY 0.787234 (-7763 3037);
PAINT MONO (-7763 3037);
FORCEPROP 1 LAST VALUE 49.9
J 2
(-7675 3100);
DISPLAY 0.510638 (-7675 3100);
PAINT SKYBLUE (-7675 3100);
FORCEPROP 1 LAST MATERIAL CHIP
J 0
(-7825 2875);
DISPLAY 0.978723 (-7825 2875);
DISPLAY INVISIBLE (-7825 2875);
FORCEPROP 1 LAST PACK_TYPE 0402LF
J 0
(-7575 2875);
DISPLAY 0.978723 (-7575 2875);
DISPLAY INVISIBLE (-7575 2875);
FORCEPROP 1 LAST WATTAGE 1/16W
J 2
(-7850 2875);
DISPLAY 0.978723 (-7850 2875);
DISPLAY INVISIBLE (-7850 2875);
FORCEPROP 1 LAST TOLERANCE 1%
J 0
(-7825 2925);
DISPLAY 0.978723 (-7825 2925);
DISPLAY INVISIBLE (-7825 2925);
FORCEPROP 1 LAST PART_NUMBER CS04992FB07
J 0
(-7875 3125);
DISPLAY 0.978723 (-7875 3125);
DISPLAY INVISIBLE (-7875 3125);
FORCEPROP 1 LAST PATH I418
J 0
(-7875 3175);
DISPLAY 0.978723 (-7875 3175);
PAINT WHITE (-7875 3175);
DISPLAY INVISIBLE (-7875 3175);
FORCEPROP 2 LAST CDS_LIB pure_quanta
J 0
(-7825 3025);
DISPLAY INVISIBLE (-7825 3025);
FORCEADD QUANTA_TITLE_BLOCK_C..1
(-100 100);
FORCEPROP 0 LAST CDS_CON_LAST_MODIFIED Fri Mar 11 14:52:56 2022
J 0
(-1985 115);
DISPLAY INVISIBLE (-1985 115);
FORCEPROP 1 LAST CUSTOM_TXT_CDS <CON_LAST_MODIFIED>
J 0
(-1985 115);
DISPLAY 0.978723 (-1985 115);
FORCEPROP 2 LAST CUSTOM_TXT_CDS <XR_PAGE_TITLE>
J 0
(-7990 5350);
DISPLAY 0.638298 (-7990 5350);
PAINT PINK (-7990 5350);
DISPLAY INVISIBLE (-7990 5350);
FORCEPROP 1 LAST CUSTOM_TXT_CDS <NAME_2>
J 0
(-3275 150);
FORCEPROP 1 LAST CUSTOM_TXT_CDS <NAME_1>
J 0
(-3275 275);
FORCEPROP 1 LAST CUSTOM_TXT_CDS <Q_NUMBER>
J 0
(-1503 203);
DISPLAY 1.212766 (-1503 203);
FORCEPROP 1 LAST CUSTOM_TXT_CDS <Q_PROJ>
J 0
(-2482 202);
DISPLAY 1.212766 (-2482 202);
FORCEPROP 1 LAST CUSTOM_TXT_CDS <Q_REV>
J 0
(-284 203);
DISPLAY 1.212766 (-284 203);
FORCEPROP 1 LAST CUSTOM_TXT_CDS <CON_PAGE_NUM> OF <CON_TOTAL_PAGES>
J 0
(-546 118);
DISPLAY 0.978723 (-546 118);
FORCEPROP 1 LAST Q_DEPT BU9
J 1
(-3863 149);
DISPLAY 1.957447 (-3863 149);
PAINT GREEN (-3863 149);
FORCEPROP 1 LAST Q_TITLE DDR5 - CPU0 CHF
J 0
(-9400 175);
DISPLAY 2.446809 (-9400 175);
PAINT GREEN (-9400 175);
FORCEPROP 2 LAST CDS_LIB pure_quanta
J 0
(-100 100);
DISPLAY INVISIBLE (-100 100);
FORCEPROP 1 LAST CDS_LMAN_SYM_OUTLINE -9475,6775,100,-125
J 0
(-100 100);
DISPLAY 0.468085 (-100 100);
PAINT GREEN (-100 100);
DISPLAY INVISIBLE (-100 100);
FORCEPROP 2 LAST PAGE_BORDER TRUE
J 0
(-7990 5350);
DISPLAY 0.638298 (-7990 5350);
PAINT PINK (-7990 5350);
DISPLAY INVISIBLE (-7990 5350);
FORCEPROP 1 LAST COMMENT_BODY TRUE
J 0
(-88 87);
DISPLAY 0.978723 (-88 87);
PAINT GREEN (-88 87);
DISPLAY INVISIBLE (-88 87);
FORCEPROP 2 LAST CDS_XR_PAGE_TITLE CR-90 : @T6G_MB_LIB.T6G(SCH_1):PAGE90
J 0
(-7990 5350);
DISPLAY 0.638298 (-7990 5350);
PAINT PINK (-7990 5350);
DISPLAY INVISIBLE (-7990 5350);
FORCEADD DNS..2
(-8400 2625);
PAINT RED (-8400 2625);
FORCEPROP 2 LAST CDS_LIB mstr_misc
J 0
(-8400 2625);
DISPLAY INVISIBLE (-8400 2625);
FORCEPROP 1 LAST COMMENT_BODY TRUE
R 1
J 0
(-8325 2400);
DISPLAY 0.872340 (-8325 2400);
PAINT PEACH (-8325 2400);
DISPLAY INVISIBLE (-8325 2400);
WIRE 17 -1 (-7825 4350)(-7825 4300);
WIRE 17 -1 (-7825 4350)(-7825 4375);
WIRE 17 -1 (-7825 4250)(-7825 4300);
WIRE 17 -1 (-7825 4250)(-7825 4200);
WIRE 17 -1 (-7825 4375)(-8325 4375);
FORCEPROP 2 LAST SIG_NAME M_F_CPU0_SA_CB<7:0>
J 0
(-8275 4385);
DISPLAY 0.489362 (-8275 4385);
WIRE 17 -1 (-7825 4150)(-7825 4200);
WIRE 17 -1 (-7825 4100)(-7825 4150);
WIRE 17 -1 (-7825 4050)(-7825 4100);
WIRE 17 -1 (-7825 4000)(-7825 4050);
WIRE 17 -1 (-7825 3900)(-7825 3850);
WIRE 17 -1 (-7825 3900)(-7825 3925);
WIRE 17 -1 (-7825 3800)(-7825 3850);
WIRE 17 -1 (-7825 3800)(-7825 3750);
WIRE 17 -1 (-7825 3925)(-8325 3925);
FORCEPROP 2 LAST SIG_NAME M_F_CPU0_SB_CB<7:0>
J 0
(-8275 3935);
DISPLAY 0.489362 (-8275 3935);
WIRE 17 -1 (-7825 5450)(-7825 5500);
WIRE 17 -1 (-7825 5500)(-7825 5550);
WIRE 17 -1 (-7825 5550)(-7825 5600);
WIRE 17 -1 (-7825 5600)(-7825 5650);
WIRE 17 -1 (-7825 5650)(-7825 5700);
WIRE 17 -1 (-7825 5700)(-7825 5750);
WIRE 17 -1 (-7825 5750)(-7825 5775);
WIRE 17 -1 (-7825 5775)(-8325 5775);
FORCEPROP 2 LAST SIG_NAME M_F_CPU0_SA_CA<6:0>
J 0
(-8310 5785);
DISPLAY 0.489362 (-8310 5785);
WIRE 17 -1 (-7825 5050)(-7825 5100);
WIRE 17 -1 (-7825 5100)(-7825 5150);
WIRE 17 -1 (-7825 5150)(-7825 5200);
WIRE 17 -1 (-7825 5200)(-7825 5250);
WIRE 17 -1 (-7825 5250)(-7825 5300);
WIRE 17 -1 (-7825 5300)(-7825 5350);
WIRE 17 -1 (-7825 5350)(-7825 5375);
WIRE 17 -1 (-7825 5375)(-8325 5375);
FORCEPROP 2 LAST SIG_NAME M_F_CPU0_SB_CA<6:0>
J 0
(-8310 5385);
DISPLAY 0.489362 (-8310 5385);
WIRE 17 -1 (-7825 3700)(-7825 3750);
WIRE 17 -1 (-7825 3650)(-7825 3700);
WIRE 17 -1 (-7825 3600)(-7825 3650);
WIRE 17 -1 (-7825 3550)(-7825 3600);
WIRE 17 -1 (-6025 5700)(-6025 5650);
WIRE 17 -1 (-6025 5750)(-6025 5700);
WIRE 17 -1 (-6025 5650)(-6025 5600);
WIRE 17 -1 (-6025 5600)(-6025 5550);
WIRE 17 -1 (-6025 5750)(-5500 5750);
FORCEPROP 2 LAST SIG_NAME M_F_CPU0_SA_DQ<31:0>
J 0
(-5960 5760);
DISPLAY 0.489362 (-5960 5760);
WIRE 17 -1 (-6025 5550)(-6025 5500);
WIRE 17 -1 (-6025 5500)(-6025 5450);
WIRE 17 -1 (-6025 5450)(-6025 5400);
WIRE 17 -1 (-6025 5400)(-6025 5350);
WIRE 17 -1 (-6025 5350)(-6025 5300);
WIRE 17 -1 (-6025 5300)(-6025 5250);
WIRE 17 -1 (-6025 5250)(-6025 5200);
WIRE 17 -1 (-6025 5200)(-6025 5150);
WIRE 17 -1 (-6025 5150)(-6025 5100);
WIRE 17 -1 (-6025 5100)(-6025 5050);
WIRE 17 -1 (-6025 5050)(-6025 5000);
WIRE 17 -1 (-6025 4950)(-6025 5000);
WIRE 17 -1 (-6025 4900)(-6025 4950);
WIRE 17 -1 (-6025 4850)(-6025 4900);
WIRE 17 -1 (-6025 4800)(-6025 4850);
WIRE 17 -1 (-6025 4800)(-6025 4750);
WIRE 17 -1 (-6025 4750)(-6025 4700);
WIRE 17 -1 (-6025 4700)(-6025 4650);
WIRE 17 -1 (-6025 4650)(-6025 4600);
WIRE 17 -1 (-6025 4600)(-6025 4550);
WIRE 17 -1 (-6025 4550)(-6025 4500);
WIRE 17 -1 (-6025 4500)(-6025 4450);
WIRE 17 -1 (-6025 4450)(-6025 4400);
WIRE 17 -1 (-6025 4350)(-6025 4400);
WIRE 17 -1 (-6025 4300)(-6025 4350);
WIRE 17 -1 (-6025 4250)(-6025 4300);
WIRE 17 -1 (-6025 4200)(-6025 4250);
WIRE 17 -1 (-6025 4100)(-6025 4050);
WIRE 17 -1 (-6025 4100)(-5500 4100);
FORCEPROP 2 LAST SIG_NAME M_F_CPU0_SB_DQ<31:0>
J 0
(-5960 4110);
DISPLAY 0.489362 (-5960 4110);
WIRE 17 -1 (-6025 4050)(-6025 4000);
WIRE 17 -1 (-6025 4000)(-6025 3950);
WIRE 17 -1 (-6025 3950)(-6025 3900);
WIRE 17 -1 (-6025 3900)(-6025 3850);
WIRE 17 -1 (-6025 3850)(-6025 3800);
WIRE 17 -1 (-6025 3800)(-6025 3750);
WIRE 17 -1 (-6025 3750)(-6025 3700);
WIRE 17 -1 (-6025 3700)(-6025 3650);
WIRE 17 -1 (-6025 3650)(-6025 3600);
WIRE 17 -1 (-6025 3600)(-6025 3550);
WIRE 17 -1 (-6025 3550)(-6025 3500);
WIRE 17 -1 (-6025 3500)(-6025 3450);
WIRE 17 -1 (-6025 3450)(-6025 3400);
WIRE 17 -1 (-6025 3400)(-6025 3350);
WIRE 17 -1 (-6025 3300)(-6025 3350);
WIRE 17 -1 (-6025 3250)(-6025 3300);
WIRE 17 -1 (-6025 3200)(-6025 3250);
WIRE 17 -1 (-6025 3150)(-6025 3200);
WIRE 17 -1 (-6025 3150)(-6025 3100);
WIRE 17 -1 (-6025 3100)(-6025 3050);
WIRE 17 -1 (-6025 3050)(-6025 3000);
WIRE 17 -1 (-6025 3000)(-6025 2950);
WIRE 17 -1 (-6025 2950)(-6025 2900);
WIRE 17 -1 (-6025 2900)(-6025 2850);
WIRE 17 -1 (-6025 2850)(-6025 2800);
WIRE 17 -1 (-6025 2800)(-6025 2750);
WIRE 17 -1 (-6025 2700)(-6025 2750);
WIRE 17 -1 (-6025 2650)(-6025 2700);
WIRE 17 -1 (-6025 2600)(-6025 2650);
WIRE 17 -1 (-6025 2550)(-6025 2600);
WIRE 17 -1 (-3325 4600)(-3325 4500);
WIRE 17 -1 (-3325 4700)(-3325 4600);
WIRE 17 -1 (-3325 4500)(-3325 4400);
WIRE 17 -1 (-3325 4300)(-3325 4400);
WIRE 17 -1 (-3325 4800)(-3325 4700);
WIRE 17 -1 (-3325 4825)(-3325 4800);
WIRE 17 -1 (-3325 4200)(-3325 4300);
WIRE 17 -1 (-3325 4100)(-3325 4200);
WIRE 17 -1 (-3325 4825)(-2625 4825);
FORCEPROP 2 LAST SIG_NAME M_F_CPU0_SA_DQS_DN<9:0>
J 0
(-3260 4835);
DISPLAY 0.489362 (-3260 4835);
WIRE 17 -1 (-3525 4550)(-3525 4450);
WIRE 17 -1 (-3525 4650)(-3525 4550);
WIRE 17 -1 (-3525 4350)(-3525 4450);
WIRE 17 -1 (-3525 4250)(-3525 4350);
WIRE 17 -1 (-3525 4750)(-3525 4650);
WIRE 17 -1 (-3525 4850)(-3525 4750);
WIRE 17 -1 (-3525 4150)(-3525 4250);
WIRE 17 -1 (-3525 4150)(-3525 4050);
WIRE 17 -1 (-3525 4875)(-3525 4850);
WIRE 17 -1 (-3525 4875)(-2625 4875);
FORCEPROP 2 LAST SIG_NAME M_F_CPU0_SA_DQS_DP<9:0>
J 0
(-3260 4885);
DISPLAY 0.489362 (-3260 4885);
WIRE 17 -1 (-3525 3700)(-3525 3600);
WIRE 17 -1 (-3525 3800)(-3525 3700);
WIRE 17 -1 (-3525 3600)(-3525 3500);
WIRE 17 -1 (-3525 3500)(-3525 3400);
WIRE 17 -1 (-3525 3825)(-3525 3800);
WIRE 17 -1 (-3525 3825)(-2625 3825);
FORCEPROP 2 LAST SIG_NAME M_F_CPU0_SB_DQS_DP<9:0>
J 0
(-3260 3835);
DISPLAY 0.489362 (-3260 3835);
WIRE 17 -1 (-3325 3650)(-3325 3550);
WIRE 17 -1 (-3325 3750)(-3325 3650);
WIRE 17 -1 (-3325 3550)(-3325 3450);
WIRE 17 -1 (-3325 3450)(-3325 3350);
WIRE 17 -1 (-3325 3775)(-3325 3750);
WIRE 17 -1 (-3325 3775)(-2625 3775);
FORCEPROP 2 LAST SIG_NAME M_F_CPU0_SB_DQS_DN<9:0>
J 0
(-3260 3785);
DISPLAY 0.489362 (-3260 3785);
WIRE 17 -1 (-3525 3300)(-3525 3400);
WIRE 17 -1 (-3525 3200)(-3525 3300);
WIRE 17 -1 (-3525 3100)(-3525 3200);
WIRE 17 -1 (-3325 4000)(-3325 3900);
WIRE 17 -1 (-3325 4100)(-3325 4000);
WIRE 17 -1 (-3525 4050)(-3525 3950);
WIRE 17 -1 (-3325 2950)(-3325 2850);
WIRE 17 -1 (-3325 3050)(-3325 2950);
WIRE 17 -1 (-3325 3050)(-3325 3150);
WIRE 17 -1 (-3325 3150)(-3325 3250);
WIRE 17 -1 (-3325 3250)(-3325 3350);
WIRE 17 -1 (-3525 3000)(-3525 2900);
WIRE 17 -1 (-3525 3100)(-3525 3000);
WIRE 16 -1 (-6400 1425)(-6400 1500);
WIRE 16 -1 (-8650 3400)(-8650 3475);
WIRE 16 -1 (-8425 2725)(-8425 2750);
WIRE 16 -1 (-7525 3175)(-8325 3175);
FORCEPROP 2 LAST SIG_NAME I3C_SPD_DDRAF_CPU0_SDA
J 0
(-8335 3185);
DISPLAY 0.489362 (-8335 3185);
WIRE 16 -1 (-7625 3125)(-7625 3025);
WIRE 16 -1 (-7525 3125)(-7625 3125);
FORCEPROP 2 LAST SIG_NAME I3C_SPD_DDRF_CPU0_SCL
J 0
(-8010 3135);
DISPLAY 0.446809 (-8010 3135);
FORCEPROP 2 LASTPROP $XRERR UNIQUE?
J 0
(-8250 3135);
DISPLAY 0.638298 (-8250 3135);
PAINT MONO (-8250 3135);
DISPLAY INVISIBLE (-8250 3135);
WIRE 16 -1 (-7625 3025)(-7725 3025);
WIRE 16 -1 (-8225 2475)(-8425 2475);
WIRE 16 -1 (-8225 2475)(-8225 2875);
WIRE 16 -1 (-8425 2525)(-8425 2475);
WIRE 16 -1 (-8425 2475)(-8450 2475);
WIRE 16 -1 (-7525 2875)(-8225 2875);
FORCEPROP 2 LAST SIG_NAME PWRGD_CHF_CPU0_DIMM
J 0
(-8125 2885);
DISPLAY 0.489362 (-8125 2885);
FORCEPROP 2 LASTPROP $XRERR UNIQUE?
J 0
(-8365 2885);
DISPLAY 0.638298 (-8365 2885);
PAINT MONO (-8365 2885);
DISPLAY INVISIBLE (-8365 2885);
WIRE 16 -1 (-7925 3025)(-8325 3025);
FORCEPROP 2 LAST SIG_NAME I3C_SPD_DDRAF_CPU0_SCL
J 0
(-8385 3035);
DISPLAY 0.489362 (-8385 3035);
WIRE 16 -1 (-8650 3675)(-8650 3700);
WIRE 16 -1 (-8650 3700)(-8550 3700);
WIRE 16 -1 (-8550 3725)(-8550 3700);
WIRE 16 -1 (-8550 3700)(-8550 3275);
WIRE 16 -1 (-8550 3275)(-7525 3275);
WIRE 16 -1 (-7525 3225)(-8325 3225);
FORCEPROP 2 LAST SIG_NAME PD_CHF_CPU0_DIMM_SAA
J 0
(-8300 3235);
DISPLAY 0.489362 (-8300 3235);
WIRE 16 -1 (-7525 2775)(-8150 2775);
FORCEPROP 2 LAST SIG_NAME TP_CHF_CPU0_DIMM_RFU_6
J 0
(-8160 2785);
DISPLAY 0.489362 (-8160 2785);
FORCEPROP 2 LASTPROP $XRERR UNIQUE?
J 0
(-8390 2775);
DISPLAY 0.638298 (-8390 2775);
PAINT MONO (-8390 2775);
DISPLAY INVISIBLE (-8390 2775);
WIRE 16 -1 (-425 5600)(-425 5550);
WIRE 16 -1 (-425 5600)(-725 5600);
WIRE 16 -1 (-425 5550)(-425 5500);
WIRE 16 -1 (-425 5550)(-725 5550);
WIRE 16 -1 (-425 5500)(-425 5450);
WIRE 16 -1 (-425 5500)(-725 5500);
WIRE 16 -1 (-425 5450)(-425 5400);
WIRE 16 -1 (-425 5450)(-725 5450);
WIRE 16 -1 (-425 5400)(-425 5350);
WIRE 16 -1 (-425 5400)(-725 5400);
WIRE 16 -1 (-425 5350)(-425 5300);
WIRE 16 -1 (-425 5350)(-725 5350);
WIRE 16 -1 (-425 5300)(-425 5250);
WIRE 16 -1 (-425 5300)(-725 5300);
WIRE 16 -1 (-425 5250)(-425 5200);
WIRE 16 -1 (-425 5250)(-725 5250);
WIRE 16 -1 (-425 5200)(-425 5150);
WIRE 16 -1 (-425 5200)(-725 5200);
WIRE 16 -1 (-425 5150)(-725 5150);
WIRE 16 -1 (-425 5150)(-425 5100);
WIRE 16 -1 (-425 5100)(-425 5050);
WIRE 16 -1 (-425 5100)(-725 5100);
WIRE 16 -1 (-425 5050)(-425 5000);
WIRE 16 -1 (-425 5050)(-725 5050);
WIRE 16 -1 (-425 5000)(-425 4950);
WIRE 16 -1 (-425 5000)(-725 5000);
WIRE 16 -1 (-425 4950)(-425 4900);
WIRE 16 -1 (-425 4950)(-725 4950);
WIRE 16 -1 (-425 4900)(-425 4850);
WIRE 16 -1 (-425 4900)(-725 4900);
WIRE 16 -1 (-425 4850)(-425 4800);
WIRE 16 -1 (-425 4850)(-725 4850);
WIRE 16 -1 (-425 4800)(-425 4750);
WIRE 16 -1 (-425 4800)(-725 4800);
WIRE 16 -1 (-425 4750)(-425 4700);
WIRE 16 -1 (-425 4750)(-725 4750);
WIRE 16 -1 (-425 4700)(-425 4650);
WIRE 16 -1 (-425 4700)(-725 4700);
WIRE 16 -1 (-425 4650)(-425 4600);
WIRE 16 -1 (-425 4650)(-725 4650);
WIRE 16 -1 (-425 4600)(-425 4550);
WIRE 16 -1 (-425 4600)(-725 4600);
WIRE 16 -1 (-425 4550)(-425 4500);
WIRE 16 -1 (-425 4550)(-725 4550);
WIRE 16 -1 (-425 4500)(-425 4450);
WIRE 16 -1 (-425 4500)(-725 4500);
WIRE 16 -1 (-425 4450)(-425 4400);
WIRE 16 -1 (-425 4450)(-725 4450);
WIRE 16 -1 (-425 4400)(-425 4350);
WIRE 16 -1 (-425 4400)(-725 4400);
WIRE 16 -1 (-425 4350)(-425 4300);
WIRE 16 -1 (-425 4350)(-725 4350);
WIRE 16 -1 (-425 4300)(-425 4250);
WIRE 16 -1 (-425 4300)(-725 4300);
WIRE 16 -1 (-425 4250)(-425 4200);
WIRE 16 -1 (-425 4250)(-725 4250);
WIRE 16 -1 (-425 4200)(-425 4150);
WIRE 16 -1 (-425 4200)(-725 4200);
WIRE 16 -1 (-425 4150)(-425 4100);
WIRE 16 -1 (-425 4150)(-725 4150);
WIRE 16 -1 (-425 4100)(-725 4100);
WIRE 16 -1 (-425 4100)(-425 4050);
WIRE 16 -1 (-425 4050)(-425 4000);
WIRE 16 -1 (-425 4050)(-725 4050);
WIRE 16 -1 (-425 4000)(-425 3950);
WIRE 16 -1 (-425 4000)(-725 4000);
WIRE 16 -1 (-425 3950)(-425 3900);
WIRE 16 -1 (-425 3950)(-725 3950);
WIRE 16 -1 (-425 3900)(-425 3850);
WIRE 16 -1 (-425 3900)(-725 3900);
WIRE 16 -1 (-425 3850)(-425 3800);
WIRE 16 -1 (-425 3850)(-725 3850);
WIRE 16 -1 (-425 3800)(-425 3750);
WIRE 16 -1 (-425 3800)(-725 3800);
WIRE 16 -1 (-425 3750)(-425 3700);
WIRE 16 -1 (-425 3750)(-725 3750);
WIRE 16 -1 (-425 3700)(-425 3650);
WIRE 16 -1 (-425 3700)(-725 3700);
WIRE 16 -1 (-425 3650)(-425 3600);
WIRE 16 -1 (-425 3650)(-725 3650);
WIRE 16 -1 (-425 3600)(-425 3550);
WIRE 16 -1 (-425 3600)(-725 3600);
WIRE 16 -1 (-425 3550)(-425 3500);
WIRE 16 -1 (-425 3550)(-725 3550);
WIRE 16 -1 (-425 3500)(-425 3450);
WIRE 16 -1 (-425 3500)(-725 3500);
WIRE 16 -1 (-425 3450)(-425 3400);
WIRE 16 -1 (-425 3450)(-725 3450);
WIRE 16 -1 (-425 3400)(-425 3350);
WIRE 16 -1 (-425 3400)(-725 3400);
WIRE 16 -1 (-425 3350)(-425 3300);
WIRE 16 -1 (-425 3350)(-725 3350);
WIRE 16 -1 (-425 3300)(-425 3250);
WIRE 16 -1 (-425 3300)(-725 3300);
WIRE 16 -1 (-425 3250)(-425 3200);
WIRE 16 -1 (-425 3250)(-725 3250);
WIRE 16 -1 (-425 3200)(-425 3150);
WIRE 16 -1 (-425 3200)(-725 3200);
WIRE 16 -1 (-425 3150)(-425 3100);
WIRE 16 -1 (-425 3150)(-725 3150);
WIRE 16 -1 (-425 3100)(-725 3100);
WIRE 16 -1 (-425 3100)(-425 3050);
WIRE 16 -1 (-425 3050)(-425 3000);
WIRE 16 -1 (-425 3050)(-725 3050);
WIRE 16 -1 (-425 3000)(-425 2950);
WIRE 16 -1 (-425 3000)(-725 3000);
WIRE 16 -1 (-425 2950)(-425 2900);
WIRE 16 -1 (-425 2950)(-725 2950);
WIRE 16 -1 (-425 2900)(-425 2850);
WIRE 16 -1 (-425 2900)(-725 2900);
WIRE 16 -1 (-425 2850)(-425 2800);
WIRE 16 -1 (-425 2850)(-725 2850);
WIRE 16 -1 (-425 2800)(-425 2750);
WIRE 16 -1 (-425 2800)(-725 2800);
WIRE 16 -1 (-425 2750)(-425 2700);
WIRE 16 -1 (-425 2750)(-725 2750);
WIRE 16 -1 (-425 2700)(-425 2650);
WIRE 16 -1 (-425 2700)(-725 2700);
WIRE 16 -1 (-425 2650)(-425 2600);
WIRE 16 -1 (-425 2650)(-725 2650);
WIRE 16 -1 (-425 2600)(-425 2550);
WIRE 16 -1 (-425 2600)(-725 2600);
WIRE 16 -1 (-425 2550)(-425 2500);
WIRE 16 -1 (-425 2550)(-725 2550);
WIRE 16 -1 (-425 2500)(-425 2450);
WIRE 16 -1 (-425 2500)(-725 2500);
WIRE 16 -1 (-425 2450)(-425 2350);
WIRE 16 -1 (-425 2450)(-725 2450);
WIRE 16 -1 (-425 2350)(-425 2300);
WIRE 16 -1 (-425 2350)(-725 2350);
WIRE 16 -1 (-425 2300)(-425 2250);
WIRE 16 -1 (-425 2300)(-725 2300);
WIRE 16 -1 (-425 2250)(-725 2250);
WIRE 16 -1 (-425 2250)(-425 2000);
WIRE 16 -1 (-2225 5500)(-1925 5500);
WIRE 16 -1 (-2225 5550)(-2225 5500);
WIRE 16 -1 (-1925 5550)(-2225 5550);
WIRE 16 -1 (-2225 5550)(-2225 5600);
WIRE 16 -1 (-1925 5600)(-2225 5600);
WIRE 16 -1 (-2225 5600)(-2225 6350);
WIRE 16 -1 (-2350 6350)(-2225 6350);
WIRE 16 -1 (-2350 6350)(-2925 6350);
WIRE 16 -1 (-2350 6350)(-2350 6250);
WIRE 16 -1 (-2925 6350)(-2925 6425);
WIRE 16 -1 (-2925 6250)(-2925 6350);
WIRE 16 -1 (-1925 2350)(-2225 2350);
WIRE 16 -1 (-2225 2400)(-2225 2350);
WIRE 16 -1 (-2225 2350)(-2225 2225);
WIRE 16 -1 (-1925 2400)(-2225 2400);
WIRE 16 -1 (-2225 2450)(-2225 2400);
WIRE 16 -1 (-1925 2450)(-2225 2450);
WIRE 16 -1 (-2225 2500)(-2225 2450);
WIRE 16 -1 (-1925 2500)(-2225 2500);
WIRE 16 -1 (-2225 2550)(-2225 2500);
WIRE 16 -1 (-1925 2550)(-2225 2550);
WIRE 16 -1 (-2225 2600)(-2225 2550);
WIRE 16 -1 (-1925 2600)(-2225 2600);
WIRE 16 -1 (-2225 2650)(-2225 2600);
WIRE 16 -1 (-1925 2650)(-2225 2650);
WIRE 16 -1 (-2225 2700)(-2225 2650);
WIRE 16 -1 (-1925 2700)(-2225 2700);
WIRE 16 -1 (-2225 2750)(-2225 2700);
WIRE 16 -1 (-1925 2750)(-2225 2750);
WIRE 16 -1 (-2225 2800)(-2225 2750);
WIRE 16 -1 (-1925 2800)(-2225 2800);
WIRE 16 -1 (-2225 2850)(-2225 2800);
WIRE 16 -1 (-1925 2850)(-2225 2850);
WIRE 16 -1 (-2225 2900)(-2225 2850);
WIRE 16 -1 (-1925 2900)(-2225 2900);
WIRE 16 -1 (-2225 2950)(-2225 2900);
WIRE 16 -1 (-1925 2950)(-2225 2950);
WIRE 16 -1 (-2225 3000)(-2225 2950);
WIRE 16 -1 (-1925 3000)(-2225 3000);
WIRE 16 -1 (-2225 3050)(-2225 3000);
WIRE 16 -1 (-1925 3050)(-2225 3050);
WIRE 16 -1 (-2225 3100)(-2225 3050);
WIRE 16 -1 (-1925 3100)(-2225 3100);
WIRE 16 -1 (-2225 3150)(-2225 3100);
WIRE 16 -1 (-1925 3150)(-2225 3150);
WIRE 16 -1 (-2225 3200)(-2225 3150);
WIRE 16 -1 (-1925 3200)(-2225 3200);
WIRE 16 -1 (-2225 3250)(-2225 3200);
WIRE 16 -1 (-1925 3250)(-2225 3250);
WIRE 16 -1 (-2225 3300)(-2225 3250);
WIRE 16 -1 (-1925 3300)(-2225 3300);
WIRE 16 -1 (-2225 3350)(-2225 3300);
WIRE 16 -1 (-1925 3350)(-2225 3350);
WIRE 16 -1 (-2225 3400)(-2225 3350);
WIRE 16 -1 (-1925 3400)(-2225 3400);
WIRE 16 -1 (-2225 3450)(-2225 3400);
WIRE 16 -1 (-1925 3450)(-2225 3450);
WIRE 16 -1 (-2225 3500)(-2225 3450);
WIRE 16 -1 (-1925 3500)(-2225 3500);
WIRE 16 -1 (-2225 3550)(-2225 3500);
WIRE 16 -1 (-1925 3550)(-2225 3550);
WIRE 16 -1 (-2225 3600)(-2225 3550);
WIRE 16 -1 (-1925 3600)(-2225 3600);
WIRE 16 -1 (-2225 3650)(-2225 3600);
WIRE 16 -1 (-1925 3650)(-2225 3650);
WIRE 16 -1 (-2225 3700)(-2225 3650);
WIRE 16 -1 (-1925 3700)(-2225 3700);
WIRE 16 -1 (-2225 3750)(-2225 3700);
WIRE 16 -1 (-1925 3750)(-2225 3750);
WIRE 16 -1 (-2225 3800)(-2225 3750);
WIRE 16 -1 (-1925 3800)(-2225 3800);
WIRE 16 -1 (-2225 3850)(-2225 3800);
WIRE 16 -1 (-1925 3850)(-2225 3850);
WIRE 16 -1 (-2225 3900)(-2225 3850);
WIRE 16 -1 (-1925 3900)(-2225 3900);
WIRE 16 -1 (-2225 3950)(-2225 3900);
WIRE 16 -1 (-1925 3950)(-2225 3950);
WIRE 16 -1 (-2225 4000)(-2225 3950);
WIRE 16 -1 (-1925 4000)(-2225 4000);
WIRE 16 -1 (-2225 4050)(-2225 4000);
WIRE 16 -1 (-2225 4100)(-2225 4050);
WIRE 16 -1 (-1925 4050)(-2225 4050);
WIRE 16 -1 (-1925 4100)(-2225 4100);
WIRE 16 -1 (-2225 4150)(-2225 4100);
WIRE 16 -1 (-1925 4150)(-2225 4150);
WIRE 16 -1 (-2225 4200)(-2225 4150);
WIRE 16 -1 (-1925 4200)(-2225 4200);
WIRE 16 -1 (-2225 4250)(-2225 4200);
WIRE 16 -1 (-1925 4250)(-2225 4250);
WIRE 16 -1 (-2225 4300)(-2225 4250);
WIRE 16 -1 (-1925 4300)(-2225 4300);
WIRE 16 -1 (-2225 4350)(-2225 4300);
WIRE 16 -1 (-1925 4350)(-2225 4350);
WIRE 16 -1 (-2225 4400)(-2225 4350);
WIRE 16 -1 (-1925 4400)(-2225 4400);
WIRE 16 -1 (-2225 4450)(-2225 4400);
WIRE 16 -1 (-1925 4450)(-2225 4450);
WIRE 16 -1 (-2225 4500)(-2225 4450);
WIRE 16 -1 (-1925 4500)(-2225 4500);
WIRE 16 -1 (-2225 4550)(-2225 4500);
WIRE 16 -1 (-1925 4550)(-2225 4550);
WIRE 16 -1 (-2225 4600)(-2225 4550);
WIRE 16 -1 (-1925 4600)(-2225 4600);
WIRE 16 -1 (-2225 4650)(-2225 4600);
WIRE 16 -1 (-1925 4650)(-2225 4650);
WIRE 16 -1 (-2225 4700)(-2225 4650);
WIRE 16 -1 (-1925 4700)(-2225 4700);
WIRE 16 -1 (-2225 4750)(-2225 4700);
WIRE 16 -1 (-1925 4750)(-2225 4750);
WIRE 16 -1 (-2225 4800)(-2225 4750);
WIRE 16 -1 (-1925 4800)(-2225 4800);
WIRE 16 -1 (-2225 4850)(-2225 4800);
WIRE 16 -1 (-1925 4850)(-2225 4850);
WIRE 16 -1 (-2225 4900)(-2225 4850);
WIRE 16 -1 (-1925 4900)(-2225 4900);
WIRE 16 -1 (-2225 4950)(-2225 4900);
WIRE 16 -1 (-1925 4950)(-2225 4950);
WIRE 16 -1 (-2225 5000)(-2225 4950);
WIRE 16 -1 (-1925 5000)(-2225 5000);
WIRE 16 -1 (-2225 5050)(-2225 5000);
WIRE 16 -1 (-1925 5050)(-2225 5050);
WIRE 16 -1 (-2225 5100)(-2225 5050);
WIRE 16 -1 (-1925 5100)(-2225 5100);
WIRE 16 -1 (-2225 5150)(-2225 5100);
WIRE 16 -1 (-1925 5150)(-2225 5150);
WIRE 16 -1 (-2225 5200)(-2225 5150);
WIRE 16 -1 (-1925 5200)(-2225 5200);
WIRE 16 -1 (-2225 5250)(-2225 5200);
WIRE 16 -1 (-1925 5250)(-2225 5250);
WIRE 16 -1 (-2225 5300)(-2225 5250);
WIRE 16 -1 (-1925 5300)(-2225 5300);
WIRE 16 -1 (-2225 5350)(-2225 5300);
WIRE 16 -1 (-1925 5350)(-2225 5350);
WIRE 16 -1 (-2225 5400)(-2225 5350);
WIRE 16 -1 (-1925 5400)(-2225 5400);
WIRE 16 -1 (-2225 5450)(-2225 5400);
WIRE 16 -1 (-1925 5450)(-2225 5450);
WIRE 16 -1 (-6125 4875)(-6325 4875);
WIRE 16 -1 (-3775 3775)(-3625 3775);
WIRE 16 -1 (-3775 3725)(-3425 3725);
WIRE 16 -1 (-3775 4825)(-3625 4825);
WIRE 16 -1 (-3775 4775)(-3425 4775);
WIRE 16 -1 (-3625 4725)(-3775 4725);
WIRE 16 -1 (-3775 4675)(-3425 4675);
WIRE 16 -1 (-3775 3525)(-3425 3525);
WIRE 16 -1 (-3625 4625)(-3775 4625);
WIRE 16 -1 (-3625 3475)(-3775 3475);
WIRE 16 -1 (-3775 3425)(-3425 3425);
WIRE 16 -1 (-3775 4475)(-3425 4475);
WIRE 16 -1 (-3775 3375)(-3625 3375);
WIRE 16 -1 (-3775 3325)(-3425 3325);
WIRE 16 -1 (-3775 4425)(-3625 4425);
WIRE 16 -1 (-3775 4375)(-3425 4375);
WIRE 16 -1 (-3625 3275)(-3775 3275);
WIRE 16 -1 (-3775 3225)(-3425 3225);
WIRE 16 -1 (-3625 4325)(-3775 4325);
WIRE 16 -1 (-3775 4275)(-3425 4275);
WIRE 16 -1 (-3625 3175)(-3775 3175);
WIRE 16 -1 (-3775 3125)(-3425 3125);
WIRE 16 -1 (-3625 4225)(-3775 4225);
WIRE 16 -1 (-3775 4175)(-3425 4175);
WIRE 16 -1 (-3625 3075)(-3775 3075);
WIRE 16 -1 (-3775 3025)(-3425 3025);
WIRE 16 -1 (-3625 4125)(-3775 4125);
WIRE 16 -1 (-3775 4075)(-3425 4075);
WIRE 16 -1 (-3775 2975)(-3625 2975);
WIRE 16 -1 (-3775 2925)(-3425 2925);
WIRE 16 -1 (-3775 4025)(-3625 4025);
WIRE 16 -1 (-3775 3975)(-3425 3975);
WIRE 16 -1 (-3625 2875)(-3775 2875);
WIRE 16 -1 (-3775 2825)(-3425 2825);
WIRE 16 -1 (-3625 3925)(-3775 3925);
WIRE 16 -1 (-3775 3875)(-3425 3875);
WIRE 16 -1 (-3625 3575)(-3775 3575);
WIRE 16 -1 (-3775 3625)(-3425 3625);
WIRE 16 -1 (-3625 3675)(-3775 3675);
WIRE 16 -1 (-3625 4525)(-3775 4525);
WIRE 16 -1 (-3775 4575)(-3425 4575);
WIRE 16 -1 (-6125 5275)(-6325 5275);
WIRE 16 -1 (-7525 4875)(-8325 4875);
FORCEPROP 2 LAST SIG_NAME M_F_CPU0_SB_PAR
J 0
(-8275 4885);
DISPLAY 0.489362 (-8275 4885);
WIRE 16 -1 (-7525 4925)(-8325 4925);
FORCEPROP 2 LAST SIG_NAME M_F_CPU0_SA_PAR
J 0
(-8275 4935);
DISPLAY 0.489362 (-8275 4935);
WIRE 16 -1 (-7525 5675)(-7725 5675);
WIRE 16 -1 (-7525 5725)(-7725 5725);
WIRE 16 -1 (-6125 5575)(-6325 5575);
WIRE 16 -1 (-6325 5725)(-6125 5725);
WIRE 16 -1 (-7525 2475)(-8150 2475);
FORCEPROP 2 LAST SIG_NAME TP_CHF_CPU0_DIMM_RFU_0
J 0
(-8160 2485);
DISPLAY 0.489362 (-8160 2485);
FORCEPROP 2 LASTPROP $XRERR UNIQUE?
J 0
(-8390 2475);
DISPLAY 0.638298 (-8390 2475);
PAINT MONO (-8390 2475);
DISPLAY INVISIBLE (-8390 2475);
WIRE 16 -1 (-7525 2525)(-8150 2525);
FORCEPROP 2 LAST SIG_NAME TP_CHF_CPU0_DIMM_RFU_1
J 0
(-8160 2535);
DISPLAY 0.489362 (-8160 2535);
FORCEPROP 2 LASTPROP $XRERR UNIQUE?
J 0
(-8390 2525);
DISPLAY 0.638298 (-8390 2525);
PAINT MONO (-8390 2525);
DISPLAY INVISIBLE (-8390 2525);
WIRE 16 -1 (-7525 2575)(-8150 2575);
FORCEPROP 2 LAST SIG_NAME TP_CHF_CPU0_DIMM_RFU_2
J 0
(-8160 2585);
DISPLAY 0.489362 (-8160 2585);
FORCEPROP 2 LASTPROP $XRERR UNIQUE?
J 0
(-8390 2575);
DISPLAY 0.638298 (-8390 2575);
PAINT MONO (-8390 2575);
DISPLAY INVISIBLE (-8390 2575);
WIRE 16 -1 (-7525 2625)(-8150 2625);
FORCEPROP 2 LAST SIG_NAME TP_CHF_CPU0_DIMM_RFU_3
J 0
(-8160 2635);
DISPLAY 0.489362 (-8160 2635);
FORCEPROP 2 LASTPROP $XRERR UNIQUE?
J 0
(-8390 2625);
DISPLAY 0.638298 (-8390 2625);
PAINT MONO (-8390 2625);
DISPLAY INVISIBLE (-8390 2625);
WIRE 16 -1 (-7525 2675)(-8150 2675);
FORCEPROP 2 LAST SIG_NAME TP_CHF_CPU0_DIMM_RFU_4
J 0
(-8160 2685);
DISPLAY 0.489362 (-8160 2685);
FORCEPROP 2 LASTPROP $XRERR UNIQUE?
J 0
(-8390 2675);
DISPLAY 0.638298 (-8390 2675);
PAINT MONO (-8390 2675);
DISPLAY INVISIBLE (-8390 2675);
WIRE 16 -1 (-7525 2725)(-8150 2725);
FORCEPROP 2 LAST SIG_NAME TP_CHF_CPU0_DIMM_RFU_5
J 0
(-8160 2735);
DISPLAY 0.489362 (-8160 2735);
FORCEPROP 2 LASTPROP $XRERR UNIQUE?
J 0
(-8390 2725);
DISPLAY 0.638298 (-8390 2725);
PAINT MONO (-8390 2725);
DISPLAY INVISIBLE (-8390 2725);
WIRE 16 -1 (-7525 3425)(-8125 3425);
FORCEPROP 2 LAST SIG_NAME M_F_CPU0_RESET_N
J 0
(-8110 3435);
DISPLAY 0.489362 (-8110 3435);
WIRE 16 -1 (-7525 2275)(-8325 2275);
FORCEPROP 2 LAST SIG_NAME M_F_CPU0_SB_RSP<0>
J 0
(-8275 2285);
DISPLAY 0.489362 (-8275 2285);
WIRE 16 -1 (-7525 2325)(-8325 2325);
FORCEPROP 2 LAST SIG_NAME M_F_CPU0_SA_RSP<0>
J 0
(-8275 2335);
DISPLAY 0.489362 (-8275 2335);
WIRE 16 -1 (-6125 2525)(-6325 2525);
WIRE 16 -1 (-6125 2575)(-6325 2575);
WIRE 16 -1 (-6125 2625)(-6325 2625);
WIRE 16 -1 (-6325 2675)(-6125 2675);
WIRE 16 -1 (-6125 2725)(-6325 2725);
WIRE 16 -1 (-6125 2775)(-6325 2775);
WIRE 16 -1 (-6125 2825)(-6325 2825);
WIRE 16 -1 (-6325 2875)(-6125 2875);
WIRE 16 -1 (-6125 2925)(-6325 2925);
WIRE 16 -1 (-6125 2975)(-6325 2975);
WIRE 16 -1 (-6125 3025)(-6325 3025);
WIRE 16 -1 (-6325 3075)(-6125 3075);
WIRE 16 -1 (-6125 3125)(-6325 3125);
WIRE 16 -1 (-6125 3175)(-6325 3175);
WIRE 16 -1 (-6125 3225)(-6325 3225);
WIRE 16 -1 (-6325 3275)(-6125 3275);
WIRE 16 -1 (-6125 3325)(-6325 3325);
WIRE 16 -1 (-6125 3375)(-6325 3375);
WIRE 16 -1 (-6125 3425)(-6325 3425);
WIRE 16 -1 (-6325 3475)(-6125 3475);
WIRE 16 -1 (-6125 3525)(-6325 3525);
WIRE 16 -1 (-6125 3575)(-6325 3575);
WIRE 16 -1 (-6125 3625)(-6325 3625);
WIRE 16 -1 (-6325 3675)(-6125 3675);
WIRE 16 -1 (-6125 3725)(-6325 3725);
WIRE 16 -1 (-6125 3775)(-6325 3775);
WIRE 16 -1 (-6125 3825)(-6325 3825);
WIRE 16 -1 (-6325 3875)(-6125 3875);
WIRE 16 -1 (-6125 3925)(-6325 3925);
WIRE 16 -1 (-6125 3975)(-6325 3975);
WIRE 16 -1 (-6125 4025)(-6325 4025);
WIRE 16 -1 (-6325 4075)(-6125 4075);
WIRE 16 -1 (-6125 4175)(-6325 4175);
WIRE 16 -1 (-6125 4225)(-6325 4225);
WIRE 16 -1 (-6125 4275)(-6325 4275);
WIRE 16 -1 (-6325 4325)(-6125 4325);
WIRE 16 -1 (-6125 4375)(-6325 4375);
WIRE 16 -1 (-6125 4425)(-6325 4425);
WIRE 16 -1 (-6125 4475)(-6325 4475);
WIRE 16 -1 (-6325 4525)(-6125 4525);
WIRE 16 -1 (-6125 4575)(-6325 4575);
WIRE 16 -1 (-6125 4625)(-6325 4625);
WIRE 16 -1 (-6125 4675)(-6325 4675);
WIRE 16 -1 (-6325 4725)(-6125 4725);
WIRE 16 -1 (-6125 4775)(-6325 4775);
WIRE 16 -1 (-6125 4825)(-6325 4825);
WIRE 16 -1 (-6325 4925)(-6125 4925);
WIRE 16 -1 (-6125 4975)(-6325 4975);
WIRE 16 -1 (-6125 5025)(-6325 5025);
WIRE 16 -1 (-6125 5075)(-6325 5075);
WIRE 16 -1 (-6325 5125)(-6125 5125);
WIRE 16 -1 (-6125 5175)(-6325 5175);
WIRE 16 -1 (-6125 5225)(-6325 5225);
WIRE 16 -1 (-6325 5325)(-6125 5325);
WIRE 16 -1 (-6125 5375)(-6325 5375);
WIRE 16 -1 (-6125 5425)(-6325 5425);
WIRE 16 -1 (-6125 5475)(-6325 5475);
WIRE 16 -1 (-6325 5525)(-6125 5525);
WIRE 16 -1 (-6125 5625)(-6325 5625);
WIRE 16 -1 (-6125 5675)(-6325 5675);
WIRE 16 -1 (-7525 4625)(-8325 4625);
FORCEPROP 2 LAST SIG_NAME M_F_CPU0_SB_CS_N<1>
J 0
(-8275 4635);
DISPLAY 0.489362 (-8275 4635);
WIRE 16 -1 (-7525 4775)(-8325 4775);
FORCEPROP 2 LAST SIG_NAME M_F_CPU0_SA_CS_N<1>
J 0
(-8275 4785);
DISPLAY 0.489362 (-8275 4785);
WIRE 16 -1 (-7525 4575)(-8325 4575);
FORCEPROP 2 LAST SIG_NAME M_F_CPU0_SB_CS_N<0>
J 0
(-8275 4585);
DISPLAY 0.489362 (-8275 4585);
WIRE 16 -1 (-7525 4725)(-8325 4725);
FORCEPROP 2 LAST SIG_NAME M_F_CPU0_SA_CS_N<0>
J 0
(-8275 4735);
DISPLAY 0.489362 (-8275 4735);
WIRE 16 -1 (-7525 4475)(-8325 4475);
FORCEPROP 2 LAST SIG_NAME M_F_CPU0_CLK_DP<0>
J 0
(-8275 4485);
DISPLAY 0.489362 (-8275 4485);
WIRE 16 -1 (-7525 4425)(-8325 4425);
FORCEPROP 2 LAST SIG_NAME M_F_CPU0_CLK_DN<0>
J 0
(-8275 4435);
DISPLAY 0.489362 (-8275 4435);
WIRE 16 -1 (-7525 3525)(-7725 3525);
WIRE 16 -1 (-7525 3575)(-7725 3575);
WIRE 16 -1 (-7525 3625)(-7725 3625);
WIRE 16 -1 (-7525 3675)(-7725 3675);
WIRE 16 -1 (-7525 3725)(-7725 3725);
WIRE 16 -1 (-7525 3775)(-7725 3775);
WIRE 16 -1 (-7525 3825)(-7725 3825);
WIRE 16 -1 (-7525 3975)(-7725 3975);
WIRE 16 -1 (-7525 4075)(-7725 4075);
WIRE 16 -1 (-7525 4125)(-7725 4125);
WIRE 16 -1 (-7525 4225)(-7725 4225);
WIRE 16 -1 (-7525 4275)(-7725 4275);
WIRE 16 -1 (-7525 5325)(-7725 5325);
WIRE 16 -1 (-7525 5275)(-7725 5275);
WIRE 16 -1 (-7525 5225)(-7725 5225);
WIRE 16 -1 (-7525 5625)(-7725 5625);
WIRE 16 -1 (-7525 5175)(-7725 5175);
WIRE 16 -1 (-7525 5575)(-7725 5575);
WIRE 16 -1 (-7525 5125)(-7725 5125);
WIRE 16 -1 (-7525 5525)(-7725 5525);
WIRE 16 -1 (-7525 5075)(-7725 5075);
WIRE 16 -1 (-7525 5475)(-7725 5475);
WIRE 16 -1 (-7525 5025)(-7725 5025);
WIRE 16 -1 (-7525 5425)(-7725 5425);
WIRE 16 -1 (-7525 3375)(-8125 3375);
FORCEPROP 2 LAST SIG_NAME M_F_CPU0_ALERT_N
J 0
(-8110 3385);
DISPLAY 0.489362 (-8110 3385);
WIRE 16 -1 (-7525 3875)(-7725 3875);
WIRE 16 -1 (-7525 4025)(-7725 4025);
WIRE 16 -1 (-7525 4175)(-7725 4175);
WIRE 16 -1 (-7525 4325)(-7725 4325);
WIRE 16 -1 (-9000 2475)(-8650 2475);
FORCEPROP 2 LAST SIG_NAME PWRGD_CHAF_CPU0
J 0
(-8985 2485);
DISPLAY 0.489362 (-8985 2485);
WIRE 16 -1 (-6400 1775)(-6400 1700);
WIRE 16 -1 (-6400 1775)(-7125 1775);
FORCEPROP 2 LAST SIG_NAME PD_CHF_CPU0_DIMM_SAA
J 0
(-7110 1785);
DISPLAY 0.489362 (-7110 1785);
WIRE 16 -1 (-2350 5925)(-2925 5925);
WIRE 16 -1 (-2350 5925)(-2350 6050);
WIRE 16 -1 (-2925 5925)(-2925 6050);
WIRE 16 -1 (-2925 5925)(-2925 5850);
DOT 1 (-8425 2475);
DOT 1 (-8550 3700);
DOT 1 (-2225 2350);
DOT 1 (-2225 2400);
DOT 1 (-2225 2450);
DOT 1 (-2225 2500);
DOT 1 (-2225 2550);
DOT 1 (-2225 2650);
DOT 1 (-2225 2600);
DOT 1 (-2225 2700);
DOT 1 (-2225 2750);
DOT 1 (-2225 2800);
DOT 1 (-2225 2900);
DOT 1 (-2225 2850);
DOT 1 (-2225 2950);
DOT 1 (-2225 3000);
DOT 1 (-2225 3050);
DOT 1 (-2225 3100);
DOT 1 (-2225 3150);
DOT 1 (-2225 3200);
DOT 1 (-2225 3250);
DOT 1 (-2225 3300);
DOT 1 (-2225 3350);
DOT 1 (-2225 3400);
DOT 1 (-2225 3450);
DOT 1 (-2225 3500);
DOT 1 (-2225 3550);
DOT 1 (-2225 3600);
DOT 1 (-2225 3650);
DOT 1 (-2225 3700);
DOT 1 (-2225 3750);
DOT 1 (-2225 3800);
DOT 1 (-2225 3850);
DOT 1 (-2225 3900);
DOT 1 (-2225 3950);
DOT 1 (-2225 4000);
DOT 1 (-2225 4050);
DOT 1 (-425 2250);
DOT 1 (-425 2300);
DOT 1 (-425 2350);
DOT 1 (-425 2450);
DOT 1 (-425 2500);
DOT 1 (-425 2550);
DOT 1 (-425 2600);
DOT 1 (-425 2650);
DOT 1 (-425 2700);
DOT 1 (-425 2750);
DOT 1 (-425 2800);
DOT 1 (-425 2900);
DOT 1 (-425 2850);
DOT 1 (-425 2950);
DOT 1 (-425 3000);
DOT 1 (-425 3050);
DOT 1 (-425 3100);
DOT 1 (-425 3150);
DOT 1 (-425 3200);
DOT 1 (-425 3250);
DOT 1 (-425 3300);
DOT 1 (-425 3350);
DOT 1 (-425 3400);
DOT 1 (-425 3450);
DOT 1 (-425 3550);
DOT 1 (-425 3500);
DOT 1 (-425 3600);
DOT 1 (-425 3650);
DOT 1 (-425 3700);
DOT 1 (-425 3800);
DOT 1 (-425 3750);
DOT 1 (-425 3850);
DOT 1 (-425 3900);
DOT 1 (-425 3950);
DOT 1 (-425 4050);
DOT 1 (-425 4000);
DOT 1 (-2225 4100);
DOT 1 (-425 4100);
DOT 1 (-2225 4150);
DOT 1 (-2225 4200);
DOT 1 (-2225 4250);
DOT 1 (-2225 4300);
DOT 1 (-2225 4350);
DOT 1 (-2225 4400);
DOT 1 (-2225 4450);
DOT 1 (-2225 4500);
DOT 1 (-2225 4550);
DOT 1 (-2225 4600);
DOT 1 (-2225 4650);
DOT 1 (-2225 4700);
DOT 1 (-2225 4750);
DOT 1 (-2225 4800);
DOT 1 (-2225 4850);
DOT 1 (-2225 4900);
DOT 1 (-2225 4950);
DOT 1 (-2225 5000);
DOT 1 (-2225 5050);
DOT 1 (-2225 5100);
DOT 1 (-2225 5150);
DOT 1 (-2225 5200);
DOT 1 (-2225 5250);
DOT 1 (-2225 5300);
DOT 1 (-2225 5350);
DOT 1 (-2225 5600);
DOT 1 (-2225 5550);
DOT 1 (-425 4150);
DOT 1 (-425 4200);
DOT 1 (-425 4250);
DOT 1 (-425 4300);
DOT 1 (-425 4350);
DOT 1 (-425 4400);
DOT 1 (-425 4450);
DOT 1 (-425 4500);
DOT 1 (-425 4550);
DOT 1 (-425 4600);
DOT 1 (-425 4650);
DOT 1 (-425 4700);
DOT 1 (-425 4750);
DOT 1 (-425 4800);
DOT 1 (-425 4850);
DOT 1 (-425 4900);
DOT 1 (-425 4950);
DOT 1 (-425 5000);
DOT 1 (-425 5050);
DOT 1 (-425 5100);
DOT 1 (-425 5150);
DOT 1 (-425 5200);
DOT 1 (-425 5250);
DOT 1 (-425 5300);
DOT 1 (-425 5350);
DOT 1 (-425 5400);
DOT 1 (-425 5450);
DOT 1 (-425 5500);
DOT 1 (-425 5550);
DOT 1 (-2925 5925);
DOT 1 (-2925 6350);
DOT 1 (-2350 6350);
DOT 1 (-2225 5400);
QUIT
